FILE_TYPE = MACRO_DRAWING;
SET COLOR_WIRE YELLOW;
SET COLOR_PROP ORANGE;
SET COLOR_DOT WHITE;
SET COLOR_ARC YELLOW;
SET COLOR_BODY GREEN;
SET COLOR_NOTE PURPLE;
SET PROP_DISPLAY VALUE;
SET PAGE_NUMBER P155;
FORCEADD TUSB8042AIRGCR..1
(-4850 3400);
FORCEPROP 1 LAST LOCATION U6002
J 0
(-5478 5939);
DISPLAY 0.723404 (-5478 5939);
PAINT GREEN (-5478 5939);
FORCEPROP 2 LAST SEC 1
J 0
(-5475 6075);
DISPLAY 0.680851 (-5475 6075);
PAINT MONO (-5475 6075);
DISPLAY INVISIBLE (-5475 6075);
FORCEPROP 2 LASTPIN (-5625 3600) $PN 50
J 2
(-5635 3610);
DISPLAY 0.680851 (-5635 3610);
PAINT MONO (-5635 3610);
FORCEPROP 2 LASTPIN (-5625 1500) $PN 60
J 2
(-5635 1510);
DISPLAY 0.680851 (-5635 1510);
PAINT MONO (-5635 1510);
FORCEPROP 2 LASTPIN (-5625 2750) $PN 46
J 2
(-5635 2760);
DISPLAY 0.680851 (-5635 2760);
PAINT MONO (-5635 2760);
FORCEPROP 2 LASTPIN (-5625 2600) $PN 47
J 2
(-5635 2610);
DISPLAY 0.680851 (-5635 2610);
PAINT MONO (-5635 2610);
FORCEPROP 2 LASTPIN (-5625 2450) $PN 44
J 2
(-5635 2460);
DISPLAY 0.680851 (-5635 2460);
PAINT MONO (-5635 2460);
FORCEPROP 2 LASTPIN (-5625 2300) $PN 43
J 2
(-5635 2310);
DISPLAY 0.680851 (-5635 2310);
PAINT MONO (-5635 2310);
FORCEPROP 2 LASTPIN (-5625 4200) $PN 36
J 2
(-5635 4210);
DISPLAY 0.680851 (-5635 4210);
PAINT MONO (-5635 4210);
FORCEPROP 2 LASTPIN (-5625 4050) $PN 35
J 2
(-5635 4060);
DISPLAY 0.680851 (-5635 4060);
PAINT MONO (-5635 4060);
FORCEPROP 2 LASTPIN (-5625 3900) $PN 33
J 2
(-5635 3910);
DISPLAY 0.680851 (-5635 3910);
PAINT MONO (-5635 3910);
FORCEPROP 2 LASTPIN (-5625 3750) $PN 32
J 2
(-5635 3760);
DISPLAY 0.680851 (-5635 3760);
PAINT MONO (-5635 3760);
FORCEPROP 2 LASTPIN (-5625 4350) $PN 41
J 2
(-5635 4360);
DISPLAY 0.680851 (-5635 4360);
PAINT MONO (-5635 4360);
FORCEPROP 2 LASTPIN (-5625 1300) $PN 49
J 2
(-5635 1310);
DISPLAY 0.680851 (-5635 1310);
PAINT MONO (-5635 1310);
FORCEPROP 2 LASTPIN (-4075 1300) $PN TH
J 0
(-4065 1310);
DISPLAY 0.680851 (-4065 1310);
PAINT MONO (-4065 1310);
FORCEPROP 2 LASTPIN (-4075 5300) $PN 2
J 0
(-4065 5310);
DISPLAY 0.680851 (-4065 5310);
PAINT MONO (-4065 5310);
FORCEPROP 2 LASTPIN (-4075 4250) $PN 10
J 0
(-4065 4260);
DISPLAY 0.680851 (-4065 4260);
PAINT MONO (-4065 4260);
FORCEPROP 2 LASTPIN (-4075 3200) $PN 18
J 0
(-4065 3210);
DISPLAY 0.680851 (-4065 3210);
PAINT MONO (-4065 3210);
FORCEPROP 2 LASTPIN (-4075 2250) $PN 25
J 0
(-4065 2260);
DISPLAY 0.680851 (-4065 2260);
PAINT MONO (-4065 2260);
FORCEPROP 2 LASTPIN (-5625 5300) $PN 54
J 2
(-5635 5310);
DISPLAY 0.680851 (-5635 5310);
PAINT MONO (-5635 5310);
FORCEPROP 2 LASTPIN (-4075 5350) $PN 1
J 0
(-4065 5360);
DISPLAY 0.680851 (-4065 5360);
PAINT MONO (-4065 5360);
FORCEPROP 2 LASTPIN (-4075 4300) $PN 9
J 0
(-4065 4310);
DISPLAY 0.680851 (-4065 4310);
PAINT MONO (-4065 4310);
FORCEPROP 2 LASTPIN (-4075 3250) $PN 17
J 0
(-4060 3260);
DISPLAY 0.680851 (-4060 3260);
PAINT MONO (-4060 3260);
FORCEPROP 2 LASTPIN (-4075 2300) $PN 24
J 0
(-4065 2310);
DISPLAY 0.680851 (-4065 2310);
PAINT MONO (-4065 2310);
FORCEPROP 2 LASTPIN (-5625 5350) $PN 53
J 2
(-5635 5360);
DISPLAY 0.680851 (-5635 5360);
PAINT MONO (-5635 5360);
FORCEPROP 2 LASTPIN (-4075 1500) $PN 64
J 0
(-4065 1510);
DISPLAY 0.680851 (-4065 1510);
PAINT MONO (-4065 1510);
FORCEPROP 2 LASTPIN (-4075 5100) $PN 7
J 0
(-4065 5110);
DISPLAY 0.680851 (-4065 5110);
PAINT MONO (-4065 5110);
FORCEPROP 2 LASTPIN (-4075 4050) $PN 15
J 0
(-4065 4060);
DISPLAY 0.680851 (-4065 4060);
PAINT MONO (-4065 4060);
FORCEPROP 2 LASTPIN (-4075 3000) $PN 23
J 0
(-4065 3010);
DISPLAY 0.680851 (-4065 3010);
PAINT MONO (-4065 3010);
FORCEPROP 2 LASTPIN (-4075 2050) $PN 30
J 0
(-4065 2060);
DISPLAY 0.680851 (-4065 2060);
PAINT MONO (-4065 2060);
FORCEPROP 2 LASTPIN (-5625 4900) $PN 59
J 2
(-5635 4910);
DISPLAY 0.680851 (-5635 4910);
PAINT MONO (-5635 4910);
FORCEPROP 2 LASTPIN (-4075 5150) $PN 6
J 0
(-4065 5160);
DISPLAY 0.680851 (-4065 5160);
PAINT MONO (-4065 5160);
FORCEPROP 2 LASTPIN (-4075 4100) $PN 14
J 0
(-4065 4110);
DISPLAY 0.680851 (-4065 4110);
PAINT MONO (-4065 4110);
FORCEPROP 2 LASTPIN (-4075 3050) $PN 22
J 0
(-4065 3060);
DISPLAY 0.680851 (-4065 3060);
PAINT MONO (-4065 3060);
FORCEPROP 2 LASTPIN (-4075 2100) $PN 29
J 0
(-4065 2110);
DISPLAY 0.680851 (-4065 2110);
PAINT MONO (-4065 2110);
FORCEPROP 2 LASTPIN (-5625 4950) $PN 58
J 2
(-5635 4960);
DISPLAY 0.680851 (-5635 4960);
PAINT MONO (-5635 4960);
FORCEPROP 2 LASTPIN (-4075 4900) $PN 4
J 0
(-4065 4910);
DISPLAY 0.680851 (-4065 4910);
PAINT MONO (-4065 4910);
FORCEPROP 2 LASTPIN (-4075 3850) $PN 12
J 0
(-4065 3860);
DISPLAY 0.680851 (-4065 3860);
PAINT MONO (-4065 3860);
FORCEPROP 2 LASTPIN (-4075 2800) $PN 20
J 0
(-4065 2810);
DISPLAY 0.680851 (-4065 2810);
PAINT MONO (-4065 2810);
FORCEPROP 2 LASTPIN (-4075 1850) $PN 27
J 0
(-4065 1860);
DISPLAY 0.680851 (-4065 1860);
PAINT MONO (-4065 1860);
FORCEPROP 2 LASTPIN (-5625 5100) $PN 56
J 2
(-5635 5110);
DISPLAY 0.680851 (-5635 5110);
PAINT MONO (-5635 5110);
FORCEPROP 2 LASTPIN (-4075 4950) $PN 3
J 0
(-4065 4960);
DISPLAY 0.680851 (-4065 4960);
PAINT MONO (-4065 4960);
FORCEPROP 2 LASTPIN (-4075 3900) $PN 11
J 0
(-4065 3910);
DISPLAY 0.680851 (-4065 3910);
PAINT MONO (-4065 3910);
FORCEPROP 2 LASTPIN (-4075 2850) $PN 19
J 0
(-4065 2860);
DISPLAY 0.680851 (-4065 2860);
PAINT MONO (-4065 2860);
FORCEPROP 2 LASTPIN (-4075 1900) $PN 26
J 0
(-4065 1910);
DISPLAY 0.680851 (-4065 1910);
PAINT MONO (-4065 1910);
FORCEPROP 2 LASTPIN (-5625 5150) $PN 55
J 2
(-5635 5160);
DISPLAY 0.680851 (-5635 5160);
PAINT MONO (-5635 5160);
FORCEPROP 2 LASTPIN (-5625 5550) $PN 48
J 2
(-5635 5560);
DISPLAY 0.680851 (-5635 5560);
PAINT MONO (-5635 5560);
FORCEPROP 1 LAST MATERIAL IC
J 0
(-5478 5665);
DISPLAY 0.723404 (-5478 5665);
PAINT GREEN (-5478 5665);
FORCEPROP 0 LAST ROOM USB3_HUB2
J 0
(-5475 6125);
DISPLAY 0.680851 (-5475 6125);
PAINT RED (-5475 6125);
FORCEPROP 2 LAST VALUE TUSB8042AIRGCR
J 0
(-5475 5975);
DISPLAY 0.680851 (-5475 5975);
FORCEPROP 2 LAST PART_TYPE SMLF
J 0
(-5475 6025);
DISPLAY 0.680851 (-5475 6025);
FORCEPROP 1 LAST NEEDS_NO_SIZE TRUE
J 0
(-4850 3400);
DISPLAY 0.723404 (-4850 3400);
PAINT GREEN (-4850 3400);
DISPLAY INVISIBLE (-4850 3400);
FORCEPROP 1 LAST CDS_LMAN_SYM_OUTLINE -625,2250,625,-2250
J 0
(-4850 3400);
DISPLAY 0.468085 (-4850 3400);
PAINT GREEN (-4850 3400);
DISPLAY INVISIBLE (-4850 3400);
FORCEPROP 2 LAST CDS_LIB pure_quanta
J 0
(-4850 3400);
DISPLAY INVISIBLE (-4850 3400);
FORCEPROP 2 LAST SEC_TYPE 
J 0
(-5475 6075);
DISPLAY 0.680851 (-5475 6075);
DISPLAY INVISIBLE (-5475 6075);
FORCEPROP 1 LAST PATH I101
J 0
(-4850 3400);
DISPLAY 0.723404 (-4850 3400);
PAINT GREEN (-4850 3400);
DISPLAY INVISIBLE (-4850 3400);
FORCEPROP 1 LAST PART_NUMBER AL008042000
J 0
(-5478 5792);
DISPLAY 0.723404 (-5478 5792);
PAINT GREEN (-5478 5792);
DISPLAY INVISIBLE (-5478 5792);
FORCEADD Q_RES..1
(-2375 5350);
FORCEPROP 1 LAST LOCATION R6271
J 0
(-2650 5350);
DISPLAY 0.808511 (-2650 5350);
FORCEPROP 0 LAST $SEC 1
J 0
(-2500 5450);
DISPLAY 0.680851 (-2500 5450);
PAINT MONO (-2500 5450);
DISPLAY INVISIBLE (-2500 5450);
FORCEPROP 0 LAST CDS_SEC 1
J 0
(-2500 5450);
DISPLAY 0.680851 (-2500 5450);
DISPLAY INVISIBLE (-2500 5450);
FORCEPROP 1 LASTPIN (-2475 5350) $PN 1
J 0
(-2463 5362);
DISPLAY 0.787234 (-2463 5362);
PAINT MONO (-2463 5362);
FORCEPROP 1 LASTPIN (-2275 5350) $PN 2
J 0
(-2313 5362);
DISPLAY 0.787234 (-2313 5362);
PAINT MONO (-2313 5362);
FORCEPROP 1 LAST TOLERANCE 5%
J 0
(-2200 5350);
DISPLAY 0.617021 (-2200 5350);
FORCEPROP 1 LAST VALUE 0
J 2
(-2225 5350);
DISPLAY 0.617021 (-2225 5350);
FORCEPROP 1 LAST PACK_TYPE 0402LF
J 0
(-2125 5350);
DISPLAY 0.617021 (-2125 5350);
FORCEPROP 1 LAST MATERIAL CHIP
J 0
(-1925 5350);
DISPLAY 0.617021 (-1925 5350);
FORCEPROP 2 LAST ROOM USB3_HUB2_MRP
J 0
(-2550 5425);
DISPLAY 0.680851 (-2550 5425);
PAINT RED (-2550 5425);
FORCEPROP 1 LAST WATTAGE 1/16W
J 2
(-2175 5300);
DISPLAY 0.617021 (-2175 5300);
DISPLAY INVISIBLE (-2175 5300);
FORCEPROP 2 LAST BOM_COST VR_SYSTEM 
J 0
(-2425 5500);
DISPLAY 0.680851 (-2425 5500);
DISPLAY INVISIBLE (-2425 5500);
FORCEPROP 2 LAST CDS_LIB pure_quanta
J 0
(-2375 5350);
DISPLAY INVISIBLE (-2375 5350);
FORCEPROP 1 LAST PATH I102
J 0
(-2425 5500);
DISPLAY 0.978723 (-2425 5500);
PAINT WHITE (-2425 5500);
DISPLAY INVISIBLE (-2425 5500);
FORCEPROP 1 LAST PART_NUMBER CS00002JB13
J 0
(-2525 5400);
DISPLAY 0.617021 (-2525 5400);
DISPLAY INVISIBLE (-2525 5400);
FORCEADD UNIVERSAL_POWER..1
(-1000 5900);
FORCEPROP 3 LASTPIN (-1000 5850) SIG_NAME P3V3_AUX\g
J 0
(-990 5860);
DISPLAY 0.659574 (-990 5860);
PAINT MONO (-990 5860);
DISPLAY INVISIBLE (-990 5860);
FORCEPROP 1 LAST HDL_POWER P3V3_AUX
J 1
(-1000 5950);
DISPLAY 0.489362 (-1000 5950);
PAINT GREEN (-1000 5950);
FORCEPROP 2 LAST BOM_COST VR_SYSTEM
J 0
(-1000 6000);
DISPLAY 0.617021 (-1000 6000);
PAINT PURPLE (-1000 6000);
DISPLAY INVISIBLE (-1000 6000);
FORCEPROP 2 LAST CDS_LIB pure_quanta_power
J 0
(-1000 5900);
DISPLAY INVISIBLE (-1000 5900);
FORCEPROP 1 LAST PATH I103
J 0
(-950 5925);
DISPLAY 0.872340 (-950 5925);
PAINT AQUA (-950 5925);
DISPLAY INVISIBLE (-950 5925);
FORCEADD Q_RES..2
(-1000 5650);
FORCEPROP 1 LAST LOCATION R6273
J 0
(-955 5775);
DISPLAY 0.638298 (-955 5775);
FORCEPROP 0 LAST $SEC 1
J 0
(-950 5875);
DISPLAY 0.680851 (-950 5875);
PAINT MONO (-950 5875);
DISPLAY INVISIBLE (-950 5875);
FORCEPROP 0 LAST CDS_SEC 1
J 0
(-950 5875);
DISPLAY 0.680851 (-950 5875);
DISPLAY INVISIBLE (-950 5875);
FORCEPROP 1 LASTPIN (-1000 5750) $PN 1
J 0
(-995 5712);
DISPLAY 0.787234 (-995 5712);
PAINT MONO (-995 5712);
FORCEPROP 1 LASTPIN (-1000 5550) $PN 2
J 0
(-995 5560);
DISPLAY 0.787234 (-995 5560);
PAINT MONO (-995 5560);
FORCEPROP 2 LAST ROOM USB3_HUB2_MRP
J 0
(-950 5825);
DISPLAY 0.680851 (-950 5825);
PAINT RED (-950 5825);
FORCEPROP 1 LAST WATTAGE 1/16W
J 0
(-960 5625);
DISPLAY 0.638298 (-960 5625);
FORCEPROP 1 LAST TOLERANCE 1%
J 0
(-955 5675);
DISPLAY 0.638298 (-955 5675);
FORCEPROP 1 LAST MATERIAL EMPTY
J 0
(-960 5575);
DISPLAY 0.638298 (-960 5575);
FORCEPROP 1 LAST VALUE 200K
J 0
(-955 5725);
DISPLAY 0.638298 (-955 5725);
FORCEPROP 1 LAST PACK_TYPE 0402LF
J 0
(-960 5475);
DISPLAY 0.638298 (-960 5475);
FORCEPROP 2 LAST CDS_LIB pure_quanta
J 0
(-1000 5650);
DISPLAY INVISIBLE (-1000 5650);
FORCEPROP 1 LAST PATH I104
J 0
(-950 5825);
DISPLAY 0.978723 (-950 5825);
PAINT WHITE (-950 5825);
DISPLAY INVISIBLE (-950 5825);
FORCEPROP 1 LAST PART_NUMBER CS42002FB05
J 0
(-960 5525);
DISPLAY 0.638298 (-960 5525);
DISPLAY INVISIBLE (-960 5525);
FORCEADD Q_RES..2
(-1000 5100);
FORCEPROP 1 LAST LOCATION R6272
J 0
(-950 5250);
DISPLAY 0.638298 (-950 5250);
FORCEPROP 0 LAST $SEC 1
J 0
(-950 5350);
DISPLAY 0.680851 (-950 5350);
PAINT MONO (-950 5350);
DISPLAY INVISIBLE (-950 5350);
FORCEPROP 0 LAST CDS_SEC 1
J 0
(-950 5350);
DISPLAY 0.680851 (-950 5350);
DISPLAY INVISIBLE (-950 5350);
FORCEPROP 1 LASTPIN (-1000 5200) $PN 1
J 0
(-995 5162);
DISPLAY 0.787234 (-995 5162);
PAINT MONO (-995 5162);
FORCEPROP 1 LASTPIN (-1000 5000) $PN 2
J 0
(-995 5010);
DISPLAY 0.787234 (-995 5010);
PAINT MONO (-995 5010);
FORCEPROP 1 LAST MATERIAL CHIP
J 0
(-950 5050);
DISPLAY 0.510638 (-950 5050);
FORCEPROP 1 LAST TOLERANCE 1%
J 0
(-950 5150);
DISPLAY 0.510638 (-950 5150);
FORCEPROP 1 LAST WATTAGE 1/16W
J 0
(-950 5100);
DISPLAY 0.510638 (-950 5100);
FORCEPROP 1 LAST VALUE 200K
J 0
(-950 5200);
DISPLAY 0.510638 (-950 5200);
FORCEPROP 1 LAST PACK_TYPE 0402LF
J 0
(-950 4950);
DISPLAY 0.510638 (-950 4950);
FORCEPROP 2 LAST ROOM USB3_HUB2_MRP
J 0
(-950 5300);
DISPLAY 0.680851 (-950 5300);
PAINT RED (-950 5300);
FORCEPROP 2 LAST CDS_LIB pure_quanta
J 0
(-1000 5100);
DISPLAY INVISIBLE (-1000 5100);
FORCEPROP 1 LAST PATH I105
J 0
(-950 5275);
DISPLAY 0.978723 (-950 5275);
PAINT WHITE (-950 5275);
DISPLAY INVISIBLE (-950 5275);
FORCEPROP 1 LAST PART_NUMBER CS42002FB05
J 0
(-950 5000);
DISPLAY 0.510638 (-950 5000);
DISPLAY INVISIBLE (-950 5000);
FORCEADD GND..1
(-1000 4875);
FORCEPROP 3 LASTPIN (-1000 4925) SIG_NAME GND\g
J 0
(-990 4935);
DISPLAY 0.659574 (-990 4935);
PAINT MONO (-990 4935);
DISPLAY INVISIBLE (-990 4935);
FORCEPROP 1 LAST SIZE 1B
J 0
(-925 4825);
DISPLAY 1.170213 (-925 4825);
PAINT AQUA (-925 4825);
DISPLAY INVISIBLE (-925 4825);
FORCEPROP 2 LAST CDS_LIB pure_quanta_power
J 0
(-1000 4875);
DISPLAY INVISIBLE (-1000 4875);
FORCEPROP 1 LAST HDL_POWER GND
J 0
(-1000 5025);
DISPLAY 1.170213 (-1000 5025);
PAINT GREEN (-1000 5025);
DISPLAY INVISIBLE (-1000 5025);
FORCEPROP 1 LAST PATH I106
J 0
(-925 4875);
DISPLAY 0.872340 (-925 4875);
PAINT AQUA (-925 4875);
DISPLAY INVISIBLE (-925 4875);
FORCEADD UNIVERSAL_POWER..1
(-8175 4025);
FORCEPROP 3 LASTPIN (-8175 3975) SIG_NAME P3V3_AUX\g
J 0
(-8165 3985);
DISPLAY 0.659574 (-8165 3985);
PAINT MONO (-8165 3985);
DISPLAY INVISIBLE (-8165 3985);
FORCEPROP 1 LAST HDL_POWER P3V3_AUX
J 1
(-8175 4075);
DISPLAY 0.489362 (-8175 4075);
PAINT GREEN (-8175 4075);
FORCEPROP 2 LAST BOM_COST VR_SYSTEM
J 0
(-8175 4125);
DISPLAY 0.617021 (-8175 4125);
PAINT PURPLE (-8175 4125);
DISPLAY INVISIBLE (-8175 4125);
FORCEPROP 2 LAST CDS_LIB pure_quanta_power
J 0
(-8175 4025);
DISPLAY INVISIBLE (-8175 4025);
FORCEPROP 1 LAST PATH I108
J 0
(-8125 4050);
DISPLAY 0.872340 (-8125 4050);
PAINT AQUA (-8125 4050);
DISPLAY INVISIBLE (-8125 4050);
FORCEADD GND..1
(-8175 3175);
FORCEPROP 3 LASTPIN (-8175 3225) SIG_NAME GND\g
J 0
(-8165 3235);
DISPLAY 0.659574 (-8165 3235);
PAINT MONO (-8165 3235);
DISPLAY INVISIBLE (-8165 3235);
FORCEPROP 1 LAST SIZE 1B
J 0
(-8100 3125);
DISPLAY 1.170213 (-8100 3125);
PAINT AQUA (-8100 3125);
DISPLAY INVISIBLE (-8100 3125);
FORCEPROP 2 LAST CDS_LIB pure_quanta_power
J 0
(-8175 3175);
DISPLAY INVISIBLE (-8175 3175);
FORCEPROP 1 LAST HDL_POWER GND
J 0
(-8175 3325);
DISPLAY 1.170213 (-8175 3325);
PAINT GREEN (-8175 3325);
DISPLAY INVISIBLE (-8175 3325);
FORCEPROP 1 LAST PATH I110
J 0
(-8100 3175);
DISPLAY 0.872340 (-8100 3175);
PAINT AQUA (-8100 3175);
DISPLAY INVISIBLE (-8100 3175);
FORCEADD Q_RES..2
R 2
(-7575 3450);
FORCEPROP 1 LAST LOCATION R6333
J 2
(-7600 3550);
DISPLAY 0.638298 (-7600 3550);
FORCEPROP 0 LAST $SEC 1
J 0
(-7600 3575);
DISPLAY 0.680851 (-7600 3575);
PAINT MONO (-7600 3575);
DISPLAY INVISIBLE (-7600 3575);
FORCEPROP 0 LAST CDS_SEC 1
J 0
(-7600 3575);
DISPLAY 0.680851 (-7600 3575);
DISPLAY INVISIBLE (-7600 3575);
FORCEPROP 1 LASTPIN (-7575 3550) $PN 1
J 2
(-7580 3512);
DISPLAY 0.787234 (-7580 3512);
PAINT MONO (-7580 3512);
FORCEPROP 1 LASTPIN (-7575 3350) $PN 2
J 2
(-7580 3360);
DISPLAY 0.787234 (-7580 3360);
PAINT MONO (-7580 3360);
FORCEPROP 1 LAST PACK_TYPE 0402LF
J 2
(-7600 3400);
DISPLAY 0.510638 (-7600 3400);
FORCEPROP 1 LAST TOLERANCE 0.1%
J 2
(-7620 3475);
DISPLAY 0.510638 (-7620 3475);
FORCEPROP 1 LAST WATTAGE 1/16W
J 2
(-7600 3450);
DISPLAY 0.510638 (-7600 3450);
FORCEPROP 1 LAST MATERIAL EMPTY
J 2
(-7600 3425);
DISPLAY 0.510638 (-7600 3425);
FORCEPROP 1 LAST VALUE 47K
J 2
(-7625 3500);
DISPLAY 0.638298 (-7625 3500);
FORCEPROP 2 LAST ROOM USB3_HUB2_TI
J 2
(-7600 3350);
DISPLAY 0.446809 (-7600 3350);
PAINT RED (-7600 3350);
FORCEPROP 2 LAST CDS_LIB pure_quanta
J 2
(-7575 3450);
DISPLAY INVISIBLE (-7575 3450);
FORCEPROP 1 LAST PATH I111
J 2
(-7625 3625);
DISPLAY 0.978723 (-7625 3625);
PAINT WHITE (-7625 3625);
DISPLAY INVISIBLE (-7625 3625);
FORCEPROP 1 LAST PART_NUMBER CS34702BB05
J 2
(-7615 3325);
DISPLAY 0.638298 (-7615 3325);
DISPLAY INVISIBLE (-7615 3325);
FORCEADD GND..1
(-7575 3275);
FORCEPROP 3 LASTPIN (-7575 3325) SIG_NAME GND\g
J 0
(-7565 3335);
DISPLAY 0.659574 (-7565 3335);
PAINT MONO (-7565 3335);
DISPLAY INVISIBLE (-7565 3335);
FORCEPROP 2 LAST CDS_LIB pure_quanta_power
J 0
(-7575 3275);
DISPLAY INVISIBLE (-7575 3275);
FORCEPROP 1 LAST SIZE 1B
J 0
(-7500 3225);
DISPLAY 1.170213 (-7500 3225);
PAINT AQUA (-7500 3225);
DISPLAY INVISIBLE (-7500 3225);
FORCEPROP 1 LAST HDL_POWER GND
J 0
(-7575 3425);
DISPLAY 1.170213 (-7575 3425);
PAINT GREEN (-7575 3425);
DISPLAY INVISIBLE (-7575 3425);
FORCEPROP 1 LAST PATH I112
J 0
(-7500 3275);
DISPLAY 0.872340 (-7500 3275);
PAINT AQUA (-7500 3275);
DISPLAY INVISIBLE (-7500 3275);
FORCEADD OFFPAGE..1
(-9025 3600);
FORCEPROP 2 LAST $XR3 235 
J 0
(-9427 3564);
DISPLAY 0.638298 (-9427 3564);
PAINT MONO (-9427 3564);
FORCEPROP 2 LAST $XR2 178 
J 0
(-9307 3564);
DISPLAY 0.638298 (-9307 3564);
PAINT MONO (-9307 3564);
FORCEPROP 2 LAST $XR1 176 
J 0
(-9427 3600);
DISPLAY 0.638298 (-9427 3600);
PAINT MONO (-9427 3600);
FORCEPROP 2 LAST $XR0 246 
J 0
(-9307 3600);
DISPLAY 0.638298 (-9307 3600);
PAINT MONO (-9307 3600);
FORCEPROP 2 LAST CDS_LIB standard
J 2
(-9025 3600);
DISPLAY INVISIBLE (-9025 3600);
FORCEPROP 1 LAST OFFPAGE TRUE
J 0
(-8700 3475);
DISPLAY 0.872340 (-8700 3475);
PAINT GREEN (-8700 3475);
DISPLAY INVISIBLE (-8700 3475);
FORCEPROP 1 LAST COMMENT_BODY TRUE
J 0
(-8900 3500);
DISPLAY 0.872340 (-8900 3500);
PAINT GREEN (-8900 3500);
DISPLAY INVISIBLE (-8900 3500);
FORCEPROP 2 LAST PATH I113
J 2
(-9225 3675);
DISPLAY 0.680851 (-9225 3675);
DISPLAY INVISIBLE (-9225 3675);
FORCEADD Q_RES..1
(-8350 3600);
FORCEPROP 1 LAST LOCATION R6328
J 0
(-8525 3550);
DISPLAY 0.638298 (-8525 3550);
FORCEPROP 0 LAST $SEC 1
J 0
(-8425 3675);
DISPLAY 0.680851 (-8425 3675);
PAINT MONO (-8425 3675);
DISPLAY INVISIBLE (-8425 3675);
FORCEPROP 0 LAST CDS_SEC 1
J 0
(-8425 3675);
DISPLAY 0.680851 (-8425 3675);
DISPLAY INVISIBLE (-8425 3675);
FORCEPROP 1 LASTPIN (-8450 3600) $PN 1
J 0
(-8438 3612);
DISPLAY 0.787234 (-8438 3612);
PAINT MONO (-8438 3612);
FORCEPROP 1 LASTPIN (-8250 3600) $PN 2
J 0
(-8288 3612);
DISPLAY 0.787234 (-8288 3612);
PAINT MONO (-8288 3612);
FORCEPROP 2 LAST ROOM USB3_HUB2_TI
J 0
(-8575 3675);
DISPLAY 0.553191 (-8575 3675);
PAINT RED (-8575 3675);
FORCEPROP 1 LAST VALUE 0
J 2
(-8250 3575);
DISPLAY 0.489362 (-8250 3575);
FORCEPROP 1 LAST TOLERANCE 5%
J 0
(-8350 3550);
DISPLAY 0.489362 (-8350 3550);
FORCEPROP 1 LAST MATERIAL CHIP
J 0
(-8300 3500);
DISPLAY 0.489362 (-8300 3500);
FORCEPROP 1 LAST PACK_TYPE 0402LF
J 0
(-8450 3500);
DISPLAY 0.489362 (-8450 3500);
FORCEPROP 2 LAST CDS_LIB pure_quanta
J 0
(-8350 3600);
DISPLAY INVISIBLE (-8350 3600);
FORCEPROP 2 LAST BOM_COST VR_SYSTEM 
J 0
(-8400 3750);
DISPLAY 0.680851 (-8400 3750);
DISPLAY INVISIBLE (-8400 3750);
FORCEPROP 1 LAST WATTAGE 1/16W
J 2
(-8150 3550);
DISPLAY 0.617021 (-8150 3550);
DISPLAY INVISIBLE (-8150 3550);
FORCEPROP 1 LAST PATH I114
J 0
(-8400 3750);
DISPLAY 0.978723 (-8400 3750);
PAINT WHITE (-8400 3750);
DISPLAY INVISIBLE (-8400 3750);
FORCEPROP 1 LAST PART_NUMBER CS00002JB13
J 0
(-8500 3650);
DISPLAY 0.617021 (-8500 3650);
DISPLAY INVISIBLE (-8500 3650);
FORCEADD Q_RES..1
(-6825 975);
FORCEPROP 1 LAST LOCATION R6323
J 0
(-7100 975);
DISPLAY 0.808511 (-7100 975);
FORCEPROP 0 LAST $SEC 1
J 0
(-6950 1075);
DISPLAY 0.680851 (-6950 1075);
PAINT MONO (-6950 1075);
DISPLAY INVISIBLE (-6950 1075);
FORCEPROP 0 LAST CDS_SEC 1
J 0
(-6950 1075);
DISPLAY 0.680851 (-6950 1075);
DISPLAY INVISIBLE (-6950 1075);
FORCEPROP 1 LASTPIN (-6925 975) $PN 1
J 0
(-6913 987);
DISPLAY 0.787234 (-6913 987);
PAINT MONO (-6913 987);
FORCEPROP 1 LASTPIN (-6725 975) $PN 2
J 0
(-6763 987);
DISPLAY 0.787234 (-6763 987);
PAINT MONO (-6763 987);
FORCEPROP 1 LAST VALUE 0
J 2
(-6675 975);
DISPLAY 0.617021 (-6675 975);
FORCEPROP 1 LAST TOLERANCE 5%
J 0
(-6650 975);
DISPLAY 0.617021 (-6650 975);
FORCEPROP 1 LAST MATERIAL CHIP
J 0
(-6700 925);
DISPLAY 0.617021 (-6700 925);
FORCEPROP 1 LAST PACK_TYPE 0402LF
J 0
(-7100 925);
DISPLAY 0.617021 (-7100 925);
FORCEPROP 2 LAST ROOM USB3_HUB2_TI
J 0
(-7000 1050);
DISPLAY 0.553191 (-7000 1050);
PAINT RED (-7000 1050);
FORCEPROP 2 LAST BOM_COST VR_SYSTEM 
J 0
(-6875 1125);
DISPLAY 0.680851 (-6875 1125);
DISPLAY INVISIBLE (-6875 1125);
FORCEPROP 1 LAST WATTAGE 1/16W
J 2
(-6625 925);
DISPLAY 0.617021 (-6625 925);
DISPLAY INVISIBLE (-6625 925);
FORCEPROP 2 LAST CDS_LIB pure_quanta
J 0
(-6825 975);
DISPLAY INVISIBLE (-6825 975);
FORCEPROP 1 LAST PATH I115
J 0
(-6875 1125);
DISPLAY 0.978723 (-6875 1125);
PAINT WHITE (-6875 1125);
DISPLAY INVISIBLE (-6875 1125);
FORCEPROP 1 LAST PART_NUMBER CS00002JB13
J 0
(-6975 1025);
DISPLAY 0.617021 (-6975 1025);
DISPLAY INVISIBLE (-6975 1025);
FORCEADD Q_RES..2
R 2
(-7925 775);
FORCEPROP 1 LAST LOCATION R6325
J 2
(-7970 900);
DISPLAY 0.638298 (-7970 900);
FORCEPROP 0 LAST $SEC 1
J 0
(-7950 950);
DISPLAY 0.680851 (-7950 950);
PAINT MONO (-7950 950);
DISPLAY INVISIBLE (-7950 950);
FORCEPROP 0 LAST CDS_SEC 1
J 0
(-7950 950);
DISPLAY 0.680851 (-7950 950);
DISPLAY INVISIBLE (-7950 950);
FORCEPROP 1 LASTPIN (-7925 875) $PN 1
J 2
(-7930 837);
DISPLAY 0.787234 (-7930 837);
PAINT MONO (-7930 837);
FORCEPROP 1 LASTPIN (-7925 675) $PN 2
J 2
(-7930 685);
DISPLAY 0.787234 (-7930 685);
PAINT MONO (-7930 685);
FORCEPROP 1 LAST WATTAGE 1/16W
J 2
(-7965 750);
DISPLAY 0.510638 (-7965 750);
FORCEPROP 1 LAST PACK_TYPE 0402LF
J 2
(-7950 650);
DISPLAY 0.510638 (-7950 650);
FORCEPROP 1 LAST MATERIAL CHIP
J 2
(-7965 700);
DISPLAY 0.510638 (-7965 700);
FORCEPROP 1 LAST TOLERANCE 1%
J 2
(-7970 800);
DISPLAY 0.510638 (-7970 800);
FORCEPROP 1 LAST VALUE 10K
J 2
(-7970 850);
DISPLAY 0.510638 (-7970 850);
FORCEPROP 2 LAST ROOM USB3_HUB2_TI
J 0
(-8250 600);
DISPLAY 0.553191 (-8250 600);
PAINT RED (-8250 600);
FORCEPROP 2 LAST CDS_LIB pure_quanta
J 0
(-7925 775);
DISPLAY INVISIBLE (-7925 775);
FORCEPROP 1 LAST PATH I116
J 2
(-7975 950);
DISPLAY 0.978723 (-7975 950);
PAINT WHITE (-7975 950);
DISPLAY INVISIBLE (-7975 950);
FORCEPROP 1 LAST PART_NUMBER CS31002FB08
J 2
(-7965 650);
DISPLAY 0.510638 (-7965 650);
DISPLAY INVISIBLE (-7965 650);
FORCEADD GND..1
(-7925 375);
FORCEPROP 3 LASTPIN (-7925 425) SIG_NAME GND\g
J 0
(-7915 435);
DISPLAY 0.659574 (-7915 435);
PAINT MONO (-7915 435);
DISPLAY INVISIBLE (-7915 435);
FORCEPROP 2 LAST CDS_LIB pure_quanta_power
J 0
(-7925 375);
DISPLAY INVISIBLE (-7925 375);
FORCEPROP 1 LAST SIZE 1B
J 0
(-7850 325);
DISPLAY 1.170213 (-7850 325);
PAINT AQUA (-7850 325);
DISPLAY INVISIBLE (-7850 325);
FORCEPROP 1 LAST HDL_POWER GND
J 0
(-7925 525);
DISPLAY 1.170213 (-7925 525);
PAINT GREEN (-7925 525);
DISPLAY INVISIBLE (-7925 525);
FORCEPROP 1 LAST PATH I117
J 0
(-7850 375);
DISPLAY 0.872340 (-7850 375);
PAINT AQUA (-7850 375);
DISPLAY INVISIBLE (-7850 375);
FORCEADD Q_RES..1
(-6875 1300);
FORCEPROP 1 LAST LOCATION R6324
J 0
(-7150 1300);
DISPLAY 0.808511 (-7150 1300);
FORCEPROP 0 LAST $SEC 1
J 0
(-7150 1350);
DISPLAY 0.680851 (-7150 1350);
PAINT MONO (-7150 1350);
DISPLAY INVISIBLE (-7150 1350);
FORCEPROP 0 LAST CDS_SEC 1
J 0
(-7150 1350);
DISPLAY 0.680851 (-7150 1350);
DISPLAY INVISIBLE (-7150 1350);
FORCEPROP 1 LASTPIN (-6975 1300) $PN 1
J 0
(-6963 1312);
DISPLAY 0.787234 (-6963 1312);
PAINT MONO (-6963 1312);
FORCEPROP 1 LASTPIN (-6775 1300) $PN 2
J 0
(-6813 1312);
DISPLAY 0.787234 (-6813 1312);
PAINT MONO (-6813 1312);
FORCEPROP 1 LAST VALUE 0
J 2
(-6725 1300);
DISPLAY 0.617021 (-6725 1300);
FORCEPROP 1 LAST TOLERANCE 5%
J 0
(-6700 1300);
DISPLAY 0.617021 (-6700 1300);
FORCEPROP 1 LAST MATERIAL CHIP
J 0
(-6725 1250);
DISPLAY 0.617021 (-6725 1250);
FORCEPROP 1 LAST PACK_TYPE 0402LF
J 0
(-7300 1250);
DISPLAY 0.617021 (-7300 1250);
FORCEPROP 2 LAST ROOM USB3_HUB2_MRP
J 0
(-7100 1250);
DISPLAY 0.553191 (-7100 1250);
PAINT RED (-7100 1250);
FORCEPROP 2 LAST CDS_LIB pure_quanta
J 0
(-6875 1300);
DISPLAY INVISIBLE (-6875 1300);
FORCEPROP 2 LAST BOM_COST VR_SYSTEM 
J 0
(-6925 1450);
DISPLAY 0.680851 (-6925 1450);
DISPLAY INVISIBLE (-6925 1450);
FORCEPROP 1 LAST WATTAGE 1/16W
J 2
(-6675 1250);
DISPLAY 0.617021 (-6675 1250);
DISPLAY INVISIBLE (-6675 1250);
FORCEPROP 1 LAST PATH I118
J 0
(-6925 1450);
DISPLAY 0.978723 (-6925 1450);
PAINT WHITE (-6925 1450);
DISPLAY INVISIBLE (-6925 1450);
FORCEPROP 1 LAST PART_NUMBER CS00002JB13
J 0
(-7025 1350);
DISPLAY 0.617021 (-7025 1350);
DISPLAY INVISIBLE (-7025 1350);
FORCEADD Q_RES..1
(-6975 5550);
FORCEPROP 1 LAST LOCATION R6316
J 0
(-7250 5550);
DISPLAY 0.808511 (-7250 5550);
FORCEPROP 0 LAST $SEC 1
J 0
(-7100 5650);
DISPLAY 0.680851 (-7100 5650);
PAINT MONO (-7100 5650);
DISPLAY INVISIBLE (-7100 5650);
FORCEPROP 0 LAST CDS_SEC 1
J 0
(-7100 5650);
DISPLAY 0.680851 (-7100 5650);
DISPLAY INVISIBLE (-7100 5650);
FORCEPROP 1 LASTPIN (-7075 5550) $PN 1
J 0
(-7063 5562);
DISPLAY 0.787234 (-7063 5562);
PAINT MONO (-7063 5562);
FORCEPROP 1 LASTPIN (-6875 5550) $PN 2
J 0
(-6913 5562);
DISPLAY 0.787234 (-6913 5562);
PAINT MONO (-6913 5562);
FORCEPROP 1 LAST VALUE 0
J 2
(-6825 5550);
DISPLAY 0.617021 (-6825 5550);
FORCEPROP 1 LAST TOLERANCE 5%
J 0
(-6800 5550);
DISPLAY 0.617021 (-6800 5550);
FORCEPROP 1 LAST MATERIAL CHIP
J 0
(-6850 5500);
DISPLAY 0.617021 (-6850 5500);
FORCEPROP 1 LAST PACK_TYPE 0402LF
J 0
(-7250 5500);
DISPLAY 0.617021 (-7250 5500);
FORCEPROP 2 LAST ROOM USB3_HUB2_TI
J 0
(-7125 5625);
DISPLAY 0.553191 (-7125 5625);
PAINT RED (-7125 5625);
FORCEPROP 1 LAST WATTAGE 1/16W
J 2
(-6775 5500);
DISPLAY 0.617021 (-6775 5500);
DISPLAY INVISIBLE (-6775 5500);
FORCEPROP 2 LAST BOM_COST VR_SYSTEM 
J 0
(-7025 5700);
DISPLAY 0.680851 (-7025 5700);
DISPLAY INVISIBLE (-7025 5700);
FORCEPROP 2 LAST CDS_LIB pure_quanta
J 0
(-6975 5550);
DISPLAY INVISIBLE (-6975 5550);
FORCEPROP 1 LAST PATH I119
J 0
(-7025 5700);
DISPLAY 0.978723 (-7025 5700);
PAINT WHITE (-7025 5700);
DISPLAY INVISIBLE (-7025 5700);
FORCEPROP 1 LAST PART_NUMBER CS00002JB13
J 0
(-7125 5600);
DISPLAY 0.617021 (-7125 5600);
DISPLAY INVISIBLE (-7125 5600);
FORCEADD GND..1
(-9100 5175);
FORCEPROP 3 LASTPIN (-9100 5225) SIG_NAME GND\g
J 0
(-9090 5235);
DISPLAY 0.659574 (-9090 5235);
PAINT MONO (-9090 5235);
DISPLAY INVISIBLE (-9090 5235);
FORCEPROP 2 LAST CDS_LIB pure_quanta_power
J 0
(-9100 5175);
DISPLAY INVISIBLE (-9100 5175);
FORCEPROP 1 LAST SIZE 1B
J 0
(-9025 5125);
DISPLAY 1.170213 (-9025 5125);
PAINT AQUA (-9025 5125);
DISPLAY INVISIBLE (-9025 5125);
FORCEPROP 1 LAST HDL_POWER GND
J 0
(-9100 5325);
DISPLAY 1.170213 (-9100 5325);
PAINT GREEN (-9100 5325);
DISPLAY INVISIBLE (-9100 5325);
FORCEPROP 1 LAST PATH I120
J 0
(-9025 5175);
DISPLAY 0.872340 (-9025 5175);
PAINT AQUA (-9025 5175);
DISPLAY INVISIBLE (-9025 5175);
FORCEADD Q_RES..2
R 2
(-9100 5400);
FORCEPROP 1 LAST LOCATION R6319
J 2
(-9145 5525);
DISPLAY 0.638298 (-9145 5525);
FORCEPROP 0 LAST $SEC 1
J 0
(-9125 5575);
DISPLAY 0.680851 (-9125 5575);
PAINT MONO (-9125 5575);
DISPLAY INVISIBLE (-9125 5575);
FORCEPROP 0 LAST CDS_SEC 1
J 0
(-9125 5575);
DISPLAY 0.680851 (-9125 5575);
DISPLAY INVISIBLE (-9125 5575);
FORCEPROP 1 LASTPIN (-9100 5500) $PN 1
J 2
(-9105 5462);
DISPLAY 0.787234 (-9105 5462);
PAINT MONO (-9105 5462);
FORCEPROP 1 LASTPIN (-9100 5300) $PN 2
J 2
(-9105 5310);
DISPLAY 0.787234 (-9105 5310);
PAINT MONO (-9105 5310);
FORCEPROP 2 LAST ROOM USB3_HUB2_TI
J 0
(-9425 5225);
DISPLAY 0.553191 (-9425 5225);
PAINT RED (-9425 5225);
FORCEPROP 1 LAST PACK_TYPE 0402LF
J 2
(-9125 5275);
DISPLAY 0.510638 (-9125 5275);
FORCEPROP 1 LAST VALUE 10K
J 2
(-9145 5475);
DISPLAY 0.510638 (-9145 5475);
FORCEPROP 1 LAST MATERIAL CHIP
J 2
(-9140 5325);
DISPLAY 0.510638 (-9140 5325);
FORCEPROP 1 LAST WATTAGE 1/16W
J 2
(-9140 5375);
DISPLAY 0.510638 (-9140 5375);
FORCEPROP 1 LAST TOLERANCE 1%
J 2
(-9145 5425);
DISPLAY 0.510638 (-9145 5425);
FORCEPROP 2 LAST CDS_LIB pure_quanta
J 0
(-9100 5400);
DISPLAY INVISIBLE (-9100 5400);
FORCEPROP 1 LAST PATH I121
J 2
(-9150 5575);
DISPLAY 0.978723 (-9150 5575);
PAINT WHITE (-9150 5575);
DISPLAY INVISIBLE (-9150 5575);
FORCEPROP 1 LAST PART_NUMBER CS31002FB08
J 2
(-9140 5275);
DISPLAY 0.510638 (-9140 5275);
DISPLAY INVISIBLE (-9140 5275);
FORCEADD P1V0_AUX..1
(-9100 6025);
FORCEPROP 3 LASTPIN (-9100 5975) SIG_NAME P5V_AUX\g
J 0
(-9090 5985);
DISPLAY 0.659574 (-9090 5985);
PAINT MONO (-9090 5985);
DISPLAY INVISIBLE (-9090 5985);
FORCEPROP 1 LAST HDL_POWER P5V_AUX
J 1
(-9090 6065);
DISPLAY 0.617021 (-9090 6065);
PAINT GREEN (-9090 6065);
FORCEPROP 2 LAST CDS_LIB pure_quanta_power
J 0
(-9100 6025);
DISPLAY INVISIBLE (-9100 6025);
FORCEPROP 2 LAST BOM_COST VR_SYSTEM 
J 0
(-9074 6101);
DISPLAY 0.680851 (-9074 6101);
DISPLAY INVISIBLE (-9074 6101);
FORCEPROP 1 LAST PATH I122
J 0
(-9050 6050);
DISPLAY 0.872340 (-9050 6050);
PAINT AQUA (-9050 6050);
DISPLAY INVISIBLE (-9050 6050);
FORCEADD Q_RES..2
R 2
(-9100 5750);
FORCEPROP 1 LAST LOCATION R6318
J 2
(-9145 5875);
DISPLAY 0.638298 (-9145 5875);
FORCEPROP 0 LAST $SEC 1
J 0
(-9325 5975);
DISPLAY 0.680851 (-9325 5975);
PAINT MONO (-9325 5975);
DISPLAY INVISIBLE (-9325 5975);
FORCEPROP 0 LAST CDS_SEC 1
J 0
(-9325 5975);
DISPLAY 0.680851 (-9325 5975);
DISPLAY INVISIBLE (-9325 5975);
FORCEPROP 1 LASTPIN (-9100 5850) $PN 1
J 2
(-9105 5812);
DISPLAY 0.787234 (-9105 5812);
PAINT MONO (-9105 5812);
FORCEPROP 1 LASTPIN (-9100 5650) $PN 2
J 2
(-9105 5660);
DISPLAY 0.787234 (-9105 5660);
PAINT MONO (-9105 5660);
FORCEPROP 1 LAST PACK_TYPE 0402LF
J 2
(-9125 5625);
DISPLAY 0.510638 (-9125 5625);
FORCEPROP 2 LAST ROOM USB3_HUB2_TI
J 0
(-9425 5925);
DISPLAY 0.553191 (-9425 5925);
PAINT RED (-9425 5925);
FORCEPROP 1 LAST TOLERANCE 1%
J 2
(-9145 5775);
DISPLAY 0.510638 (-9145 5775);
FORCEPROP 1 LAST MATERIAL CHIP
J 2
(-9140 5675);
DISPLAY 0.510638 (-9140 5675);
FORCEPROP 1 LAST WATTAGE 1/16W
J 2
(-9140 5725);
DISPLAY 0.510638 (-9140 5725);
FORCEPROP 1 LAST VALUE 90.9K
J 2
(-9145 5825);
DISPLAY 0.510638 (-9145 5825);
FORCEPROP 2 LAST CDS_LIB pure_quanta
J 2
(-9100 5750);
DISPLAY INVISIBLE (-9100 5750);
FORCEPROP 1 LAST PATH I123
J 2
(-9150 5925);
DISPLAY 0.978723 (-9150 5925);
PAINT WHITE (-9150 5925);
DISPLAY INVISIBLE (-9150 5925);
FORCEPROP 1 LAST PART_NUMBER CS39092FB04
J 2
(-9140 5625);
DISPLAY 0.510638 (-9140 5625);
DISPLAY INVISIBLE (-9140 5625);
FORCEADD Q_RES..1
(-6975 6025);
FORCEPROP 1 LAST LOCATION R6317
J 0
(-7250 6025);
DISPLAY 0.808511 (-7250 6025);
FORCEPROP 0 LAST $SEC 1
J 0
(-6525 6075);
DISPLAY 0.680851 (-6525 6075);
PAINT MONO (-6525 6075);
DISPLAY INVISIBLE (-6525 6075);
FORCEPROP 0 LAST CDS_SEC 1
J 0
(-6525 6075);
DISPLAY 0.680851 (-6525 6075);
DISPLAY INVISIBLE (-6525 6075);
FORCEPROP 1 LASTPIN (-7075 6025) $PN 1
J 0
(-7063 6037);
DISPLAY 0.787234 (-7063 6037);
PAINT MONO (-7063 6037);
FORCEPROP 1 LASTPIN (-6875 6025) $PN 2
J 0
(-6913 6037);
DISPLAY 0.787234 (-6913 6037);
PAINT MONO (-6913 6037);
FORCEPROP 1 LAST PACK_TYPE 0402LF
J 0
(-7250 5975);
DISPLAY 0.617021 (-7250 5975);
FORCEPROP 2 LAST ROOM USB3_HUB2_MRP
J 0
(-7125 6100);
DISPLAY 0.553191 (-7125 6100);
PAINT RED (-7125 6100);
FORCEPROP 1 LAST VALUE 0
J 2
(-6825 6025);
DISPLAY 0.617021 (-6825 6025);
FORCEPROP 1 LAST TOLERANCE 5%
J 0
(-6800 6025);
DISPLAY 0.617021 (-6800 6025);
FORCEPROP 1 LAST MATERIAL CHIP
J 0
(-6850 5975);
DISPLAY 0.617021 (-6850 5975);
FORCEPROP 2 LAST CDS_LIB pure_quanta
J 0
(-6975 6025);
DISPLAY INVISIBLE (-6975 6025);
FORCEPROP 2 LAST BOM_COST VR_SYSTEM 
J 0
(-7025 6175);
DISPLAY 0.680851 (-7025 6175);
DISPLAY INVISIBLE (-7025 6175);
FORCEPROP 1 LAST WATTAGE 1/16W
J 2
(-6775 5975);
DISPLAY 0.617021 (-6775 5975);
DISPLAY INVISIBLE (-6775 5975);
FORCEPROP 1 LAST PATH I124
J 0
(-7025 6175);
DISPLAY 0.978723 (-7025 6175);
PAINT WHITE (-7025 6175);
DISPLAY INVISIBLE (-7025 6175);
FORCEPROP 1 LAST PART_NUMBER CS00002JB13
J 0
(-7125 6075);
DISPLAY 0.617021 (-7125 6075);
DISPLAY INVISIBLE (-7125 6075);
FORCEADD UNIVERSAL_POWER..1
(-8025 6550);
FORCEPROP 3 LASTPIN (-8025 6500) SIG_NAME P3V3_AUX\g
J 0
(-8015 6510);
DISPLAY 0.659574 (-8015 6510);
PAINT MONO (-8015 6510);
DISPLAY INVISIBLE (-8015 6510);
FORCEPROP 1 LAST HDL_POWER P3V3_AUX
J 1
(-8025 6600);
DISPLAY 0.489362 (-8025 6600);
PAINT GREEN (-8025 6600);
FORCEPROP 2 LAST CDS_LIB pure_quanta_power
J 0
(-8025 6550);
DISPLAY INVISIBLE (-8025 6550);
FORCEPROP 2 LAST BOM_COST VR_SYSTEM
J 0
(-8025 6650);
DISPLAY 0.617021 (-8025 6650);
PAINT PURPLE (-8025 6650);
DISPLAY INVISIBLE (-8025 6650);
FORCEPROP 1 LAST PATH I126
J 0
(-7975 6575);
DISPLAY 0.872340 (-7975 6575);
PAINT AQUA (-7975 6575);
DISPLAY INVISIBLE (-7975 6575);
FORCEADD Q_CAP..1
(-8025 5875);
FORCEPROP 1 LAST LOCATION C6088
J 0
(-8200 5900);
DISPLAY 0.787234 (-8200 5900);
FORCEPROP 0 LAST $SEC 1
J 0
(-7975 6025);
DISPLAY 0.680851 (-7975 6025);
PAINT MONO (-7975 6025);
DISPLAY INVISIBLE (-7975 6025);
FORCEPROP 0 LAST CDS_SEC 1
J 0
(-7975 6025);
DISPLAY 0.680851 (-7975 6025);
DISPLAY INVISIBLE (-7975 6025);
FORCEPROP 1 LASTPIN (-8025 5975) $PN 1
J 0
(-8015 5955);
DISPLAY 0.787234 (-8015 5955);
PAINT MONO (-8015 5955);
FORCEPROP 1 LASTPIN (-8025 5775) $PN 2
J 0
(-8015 5755);
DISPLAY 0.787234 (-8015 5755);
PAINT MONO (-8015 5755);
FORCEPROP 2 LAST ROOM USB3_HUB2_MRP
J 0
(-7975 5650);
DISPLAY 0.553191 (-7975 5650);
PAINT RED (-7975 5650);
FORCEPROP 1 LAST PACK_TYPE C0805
J 0
(-7975 5700);
DISPLAY 0.489362 (-7975 5700);
FORCEPROP 1 LAST VOLTAGE 16V
J 0
(-7975 5900);
DISPLAY 0.489362 (-7975 5900);
FORCEPROP 1 LAST VALUE 10UF
J 0
(-7975 5950);
DISPLAY 0.489362 (-7975 5950);
FORCEPROP 1 LAST TOLERANCE 10%
J 0
(-7975 5850);
DISPLAY 0.489362 (-7975 5850);
FORCEPROP 1 LAST MATERIAL X6S
J 0
(-7975 5800);
DISPLAY 0.489362 (-7975 5800);
FORCEPROP 2 LAST CDS_LIB pure_quanta
J 0
(-8025 5875);
DISPLAY INVISIBLE (-8025 5875);
FORCEPROP 2 LAST BOM_COST VR_SYSTEM 
J 0
(-7975 6025);
DISPLAY 0.680851 (-7975 6025);
DISPLAY INVISIBLE (-7975 6025);
FORCEPROP 1 LAST PATH I127
J 0
(-7975 6025);
DISPLAY 0.978723 (-7975 6025);
PAINT WHITE (-7975 6025);
DISPLAY INVISIBLE (-7975 6025);
FORCEPROP 1 LAST PART_NUMBER CH6103KEA00
J 0
(-7975 5750);
DISPLAY 0.489362 (-7975 5750);
DISPLAY INVISIBLE (-7975 5750);
FORCEADD GND..1
(-8025 5650);
FORCEPROP 3 LASTPIN (-8025 5700) SIG_NAME GND\g
J 0
(-8015 5710);
DISPLAY 0.659574 (-8015 5710);
PAINT MONO (-8015 5710);
DISPLAY INVISIBLE (-8015 5710);
FORCEPROP 1 LAST SIZE 1B
J 0
(-7950 5600);
DISPLAY 1.170213 (-7950 5600);
PAINT AQUA (-7950 5600);
DISPLAY INVISIBLE (-7950 5600);
FORCEPROP 2 LAST CDS_LIB pure_quanta_power
J 0
(-8025 5650);
DISPLAY INVISIBLE (-8025 5650);
FORCEPROP 1 LAST HDL_POWER GND
J 0
(-8025 5800);
DISPLAY 1.170213 (-8025 5800);
PAINT GREEN (-8025 5800);
DISPLAY INVISIBLE (-8025 5800);
FORCEPROP 1 LAST PATH I128
J 0
(-7950 5650);
DISPLAY 0.872340 (-7950 5650);
PAINT AQUA (-7950 5650);
DISPLAY INVISIBLE (-7950 5650);
FORCEADD Q_RES..2
(-8350 5900);
FORCEPROP 1 LAST LOCATION R6321
J 0
(-8525 5975);
DISPLAY 0.808511 (-8525 5975);
FORCEPROP 0 LAST $SEC 1
J 0
(-8300 6075);
DISPLAY 0.680851 (-8300 6075);
PAINT MONO (-8300 6075);
DISPLAY INVISIBLE (-8300 6075);
FORCEPROP 0 LAST CDS_SEC 1
J 0
(-8300 6075);
DISPLAY 0.680851 (-8300 6075);
DISPLAY INVISIBLE (-8300 6075);
FORCEPROP 1 LASTPIN (-8350 6000) $PN 1
J 0
(-8345 5962);
DISPLAY 0.787234 (-8345 5962);
PAINT MONO (-8345 5962);
FORCEPROP 1 LASTPIN (-8350 5800) $PN 2
J 0
(-8345 5810);
DISPLAY 0.787234 (-8345 5810);
PAINT MONO (-8345 5810);
FORCEPROP 1 LAST TOLERANCE 0.1%
J 0
(-8500 5875);
DISPLAY 0.638298 (-8500 5875);
FORCEPROP 1 LAST MATERIAL EMPTY
J 0
(-8525 5825);
DISPLAY 0.638298 (-8525 5825);
FORCEPROP 1 LAST PACK_TYPE 0402LF
J 0
(-8550 5725);
DISPLAY 0.638298 (-8550 5725);
FORCEPROP 1 LAST VALUE 47K
J 0
(-8475 5925);
DISPLAY 0.638298 (-8475 5925);
FORCEPROP 2 LAST ROOM USB3_HUB2_MRP
J 0
(-8775 5675);
DISPLAY 0.680851 (-8775 5675);
PAINT RED (-8775 5675);
FORCEPROP 2 LAST CDS_LIB pure_quanta
J 0
(-8350 5900);
DISPLAY INVISIBLE (-8350 5900);
FORCEPROP 1 LAST WATTAGE 1/16W
J 0
(-8525 5875);
DISPLAY 0.638298 (-8525 5875);
DISPLAY INVISIBLE (-8525 5875);
FORCEPROP 1 LAST PATH I129
J 0
(-8300 6075);
DISPLAY 0.978723 (-8300 6075);
PAINT WHITE (-8300 6075);
DISPLAY INVISIBLE (-8300 6075);
FORCEPROP 1 LAST PART_NUMBER CS34702BB05
J 0
(-8675 5775);
DISPLAY 0.638298 (-8675 5775);
DISPLAY INVISIBLE (-8675 5775);
FORCEADD GND..1
(-8350 5650);
FORCEPROP 3 LASTPIN (-8350 5700) SIG_NAME GND\g
J 0
(-8340 5710);
DISPLAY 0.659574 (-8340 5710);
PAINT MONO (-8340 5710);
DISPLAY INVISIBLE (-8340 5710);
FORCEPROP 2 LAST CDS_LIB pure_quanta_power
J 0
(-8350 5650);
DISPLAY INVISIBLE (-8350 5650);
FORCEPROP 1 LAST SIZE 1B
J 0
(-8275 5600);
DISPLAY 1.170213 (-8275 5600);
PAINT AQUA (-8275 5600);
DISPLAY INVISIBLE (-8275 5600);
FORCEPROP 1 LAST HDL_POWER GND
J 0
(-8350 5800);
DISPLAY 1.170213 (-8350 5800);
PAINT GREEN (-8350 5800);
DISPLAY INVISIBLE (-8350 5800);
FORCEPROP 1 LAST PATH I130
J 0
(-8275 5650);
DISPLAY 0.872340 (-8275 5650);
PAINT AQUA (-8275 5650);
DISPLAY INVISIBLE (-8275 5650);
FORCEADD Q_RES..1
(-8600 6275);
FORCEPROP 1 LAST LOCATION R6322
J 0
(-8675 6375);
DISPLAY 0.808511 (-8675 6375);
FORCEPROP 0 LAST $SEC 1
J 0
(-8650 6375);
DISPLAY 0.680851 (-8650 6375);
PAINT MONO (-8650 6375);
DISPLAY INVISIBLE (-8650 6375);
FORCEPROP 0 LAST CDS_SEC 1
J 0
(-8650 6375);
DISPLAY 0.680851 (-8650 6375);
DISPLAY INVISIBLE (-8650 6375);
FORCEPROP 1 LASTPIN (-8700 6275) $PN 1
J 0
(-8688 6287);
DISPLAY 0.787234 (-8688 6287);
PAINT MONO (-8688 6287);
FORCEPROP 1 LASTPIN (-8500 6275) $PN 2
J 0
(-8538 6287);
DISPLAY 0.787234 (-8538 6287);
PAINT MONO (-8538 6287);
FORCEPROP 2 LAST ROOM USB3_HUB2_MRP
J 0
(-8775 6200);
DISPLAY 0.680851 (-8775 6200);
PAINT RED (-8775 6200);
FORCEPROP 1 LAST MATERIAL CHIP
J 0
(-8650 6325);
DISPLAY 0.617021 (-8650 6325);
FORCEPROP 1 LAST VALUE 0
J 2
(-8450 6275);
DISPLAY 0.617021 (-8450 6275);
FORCEPROP 1 LAST TOLERANCE 5%
J 0
(-8425 6275);
DISPLAY 0.617021 (-8425 6275);
FORCEPROP 1 LAST WATTAGE 1/16W
J 2
(-8400 6225);
DISPLAY 0.617021 (-8400 6225);
DISPLAY INVISIBLE (-8400 6225);
FORCEPROP 2 LAST BOM_COST VR_SYSTEM 
J 0
(-8650 6425);
DISPLAY 0.680851 (-8650 6425);
DISPLAY INVISIBLE (-8650 6425);
FORCEPROP 2 LAST CDS_LIB pure_quanta
J 0
(-8600 6275);
DISPLAY INVISIBLE (-8600 6275);
FORCEPROP 1 LAST PACK_TYPE 0402LF
J 0
(-8350 6275);
DISPLAY 0.617021 (-8350 6275);
DISPLAY INVISIBLE (-8350 6275);
FORCEPROP 1 LAST PATH I131
J 0
(-8650 6425);
DISPLAY 0.978723 (-8650 6425);
PAINT WHITE (-8650 6425);
DISPLAY INVISIBLE (-8650 6425);
FORCEPROP 1 LAST PART_NUMBER CS00002JB13
J 0
(-8750 6325);
DISPLAY 0.617021 (-8750 6325);
DISPLAY INVISIBLE (-8750 6325);
FORCEADD OFFPAGE..1
(-9150 6275);
FORCEPROP 2 LAST $XR3 235 
J 0
(-9432 6203);
DISPLAY 0.638298 (-9432 6203);
PAINT MONO (-9432 6203);
FORCEPROP 2 LAST $XR2 178 
J 0
(-9432 6311);
DISPLAY 0.638298 (-9432 6311);
PAINT MONO (-9432 6311);
FORCEPROP 2 LAST $XR1 176 
J 0
(-9432 6239);
DISPLAY 0.638298 (-9432 6239);
PAINT MONO (-9432 6239);
FORCEPROP 2 LAST $XR0 246 
J 0
(-9432 6275);
DISPLAY 0.638298 (-9432 6275);
PAINT MONO (-9432 6275);
FORCEPROP 2 LAST CDS_LIB standard
J 2
(-9150 6275);
DISPLAY INVISIBLE (-9150 6275);
FORCEPROP 1 LAST OFFPAGE TRUE
J 0
(-8825 6150);
DISPLAY 0.872340 (-8825 6150);
PAINT GREEN (-8825 6150);
DISPLAY INVISIBLE (-8825 6150);
FORCEPROP 1 LAST COMMENT_BODY TRUE
J 0
(-9025 6175);
DISPLAY 0.872340 (-9025 6175);
PAINT GREEN (-9025 6175);
DISPLAY INVISIBLE (-9025 6175);
FORCEPROP 2 LAST PATH I132
J 2
(-9350 6325);
DISPLAY 0.680851 (-9350 6325);
DISPLAY INVISIBLE (-9350 6325);
FORCEADD UNIVERSAL_POWER..1
(-1775 5250);
FORCEPROP 3 LASTPIN (-1775 5200) SIG_NAME P1V2_CPU0_USB2_DVDD12\g
J 0
(-1765 5210);
DISPLAY 0.659574 (-1765 5210);
PAINT MONO (-1765 5210);
DISPLAY INVISIBLE (-1765 5210);
FORCEPROP 1 LAST HDL_POWER P1V2_CPU0_USB2_DVDD12
J 1
(-1775 5300);
DISPLAY 0.617021 (-1775 5300);
PAINT GREEN (-1775 5300);
FORCEPROP 2 LAST BOM_COST VR_SYSTEM
J 0
(-1775 5350);
DISPLAY 0.617021 (-1775 5350);
PAINT PURPLE (-1775 5350);
DISPLAY INVISIBLE (-1775 5350);
FORCEPROP 2 LAST CDS_LIB pure_quanta_power
J 0
(-1775 5250);
DISPLAY INVISIBLE (-1775 5250);
FORCEPROP 1 LAST PATH I133
J 0
(-1725 5275);
DISPLAY 0.872340 (-1725 5275);
PAINT AQUA (-1725 5275);
DISPLAY INVISIBLE (-1725 5275);
FORCEADD Q_RES..1
(-2500 5150);
FORCEPROP 1 LAST LOCATION R6261
J 0
(-2775 5150);
DISPLAY 0.808511 (-2775 5150);
FORCEPROP 0 LAST $SEC 1
J 0
(-2625 5250);
DISPLAY 0.680851 (-2625 5250);
PAINT MONO (-2625 5250);
DISPLAY INVISIBLE (-2625 5250);
FORCEPROP 0 LAST CDS_SEC 1
J 0
(-2625 5250);
DISPLAY 0.680851 (-2625 5250);
DISPLAY INVISIBLE (-2625 5250);
FORCEPROP 1 LASTPIN (-2600 5150) $PN 1
J 0
(-2588 5162);
DISPLAY 0.787234 (-2588 5162);
PAINT MONO (-2588 5162);
FORCEPROP 1 LASTPIN (-2400 5150) $PN 2
J 0
(-2438 5162);
DISPLAY 0.787234 (-2438 5162);
PAINT MONO (-2438 5162);
FORCEPROP 1 LAST TOLERANCE 5%
J 0
(-2325 5150);
DISPLAY 0.617021 (-2325 5150);
FORCEPROP 1 LAST VALUE 0
J 2
(-2350 5150);
DISPLAY 0.617021 (-2350 5150);
FORCEPROP 1 LAST MATERIAL CHIP
J 0
(-2050 5150);
DISPLAY 0.617021 (-2050 5150);
FORCEPROP 2 LAST ROOM USB3_HUB2_MRP
J 0
(-2700 5225);
DISPLAY 0.680851 (-2700 5225);
PAINT RED (-2700 5225);
FORCEPROP 1 LAST PACK_TYPE 0402LF
J 0
(-2250 5150);
DISPLAY 0.617021 (-2250 5150);
FORCEPROP 2 LAST BOM_COST VR_SYSTEM 
J 0
(-2550 5300);
DISPLAY 0.680851 (-2550 5300);
DISPLAY INVISIBLE (-2550 5300);
FORCEPROP 1 LAST WATTAGE 1/16W
J 2
(-2300 5100);
DISPLAY 0.617021 (-2300 5100);
DISPLAY INVISIBLE (-2300 5100);
FORCEPROP 2 LAST CDS_LIB pure_quanta
J 0
(-2500 5150);
DISPLAY INVISIBLE (-2500 5150);
FORCEPROP 1 LAST PATH I134
J 0
(-2550 5300);
DISPLAY 0.978723 (-2550 5300);
PAINT WHITE (-2550 5300);
DISPLAY INVISIBLE (-2550 5300);
FORCEPROP 1 LAST PART_NUMBER CS00002JB13
J 0
(-2650 5200);
DISPLAY 0.617021 (-2650 5200);
DISPLAY INVISIBLE (-2650 5200);
FORCEADD UNIVERSAL_POWER..1
(-1300 3100);
FORCEPROP 3 LASTPIN (-1300 3050) SIG_NAME P1V2_CPU0_USB2_DVDD12\g
J 0
(-1290 3060);
DISPLAY 0.659574 (-1290 3060);
PAINT MONO (-1290 3060);
DISPLAY INVISIBLE (-1290 3060);
FORCEPROP 1 LAST HDL_POWER P1V2_CPU0_USB2_DVDD12
J 1
(-1275 3125);
DISPLAY 0.617021 (-1275 3125);
PAINT GREEN (-1275 3125);
FORCEPROP 2 LAST CDS_LIB pure_quanta_power
J 0
(-1300 3100);
DISPLAY INVISIBLE (-1300 3100);
FORCEPROP 2 LAST BOM_COST VR_SYSTEM
J 0
(-1300 3200);
DISPLAY 0.617021 (-1300 3200);
PAINT PURPLE (-1300 3200);
DISPLAY INVISIBLE (-1300 3200);
FORCEPROP 1 LAST PATH I135
J 0
(-1250 3125);
DISPLAY 0.872340 (-1250 3125);
PAINT AQUA (-1250 3125);
DISPLAY INVISIBLE (-1250 3125);
FORCEADD Q_RES..1
(-2450 3000);
FORCEPROP 1 LAST LOCATION R6266
J 0
(-2725 3000);
DISPLAY 0.808511 (-2725 3000);
FORCEPROP 0 LAST $SEC 1
J 0
(-2575 3100);
DISPLAY 0.680851 (-2575 3100);
PAINT MONO (-2575 3100);
DISPLAY INVISIBLE (-2575 3100);
FORCEPROP 0 LAST CDS_SEC 1
J 0
(-2575 3100);
DISPLAY 0.680851 (-2575 3100);
DISPLAY INVISIBLE (-2575 3100);
FORCEPROP 1 LASTPIN (-2550 3000) $PN 1
J 0
(-2538 3012);
DISPLAY 0.787234 (-2538 3012);
PAINT MONO (-2538 3012);
FORCEPROP 1 LASTPIN (-2350 3000) $PN 2
J 0
(-2388 3012);
DISPLAY 0.787234 (-2388 3012);
PAINT MONO (-2388 3012);
FORCEPROP 2 LAST ROOM USB3_HUB2_MRP
J 0
(-2575 3050);
DISPLAY 0.680851 (-2575 3050);
PAINT RED (-2575 3050);
FORCEPROP 1 LAST TOLERANCE 5%
J 0
(-2275 3000);
DISPLAY 0.617021 (-2275 3000);
FORCEPROP 1 LAST PACK_TYPE 0402LF
J 0
(-2200 3000);
DISPLAY 0.617021 (-2200 3000);
FORCEPROP 1 LAST MATERIAL CHIP
J 0
(-2000 3000);
DISPLAY 0.617021 (-2000 3000);
FORCEPROP 1 LAST VALUE 0
J 2
(-2300 3000);
DISPLAY 0.617021 (-2300 3000);
FORCEPROP 1 LAST WATTAGE 1/16W
J 2
(-2250 2950);
DISPLAY 0.617021 (-2250 2950);
DISPLAY INVISIBLE (-2250 2950);
FORCEPROP 2 LAST BOM_COST VR_SYSTEM 
J 0
(-2500 3150);
DISPLAY 0.680851 (-2500 3150);
DISPLAY INVISIBLE (-2500 3150);
FORCEPROP 2 LAST CDS_LIB pure_quanta
J 0
(-2450 3000);
DISPLAY INVISIBLE (-2450 3000);
FORCEPROP 1 LAST PATH I136
J 0
(-2500 3150);
DISPLAY 0.978723 (-2500 3150);
PAINT WHITE (-2500 3150);
DISPLAY INVISIBLE (-2500 3150);
FORCEPROP 1 LAST PART_NUMBER CS00002JB13
J 0
(-2600 3050);
DISPLAY 0.617021 (-2600 3050);
DISPLAY INVISIBLE (-2600 3050);
FORCEADD Q_RES..1
(-7550 2525);
FORCEPROP 1 LAST LOCATION R6314
J 0
(-7825 2525);
DISPLAY 0.808511 (-7825 2525);
FORCEPROP 0 LAST $SEC 1
J 0
(-7100 2575);
DISPLAY 0.680851 (-7100 2575);
PAINT MONO (-7100 2575);
DISPLAY INVISIBLE (-7100 2575);
FORCEPROP 0 LAST CDS_SEC 1
J 0
(-7100 2575);
DISPLAY 0.680851 (-7100 2575);
DISPLAY INVISIBLE (-7100 2575);
FORCEPROP 1 LASTPIN (-7650 2525) $PN 1
J 0
(-7638 2537);
DISPLAY 0.787234 (-7638 2537);
PAINT MONO (-7638 2537);
FORCEPROP 1 LASTPIN (-7450 2525) $PN 2
J 0
(-7488 2537);
DISPLAY 0.787234 (-7488 2537);
PAINT MONO (-7488 2537);
FORCEPROP 2 LAST ROOM USB3_HUB2_MRP
J 0
(-7875 2500);
DISPLAY 0.446809 (-7875 2500);
PAINT RED (-7875 2500);
FORCEPROP 1 LAST PACK_TYPE 0402LF
J 0
(-7300 2525);
DISPLAY 0.617021 (-7300 2525);
FORCEPROP 1 LAST MATERIAL CHIP
J 0
(-7100 2525);
DISPLAY 0.617021 (-7100 2525);
FORCEPROP 1 LAST TOLERANCE 5%
J 0
(-7375 2525);
DISPLAY 0.617021 (-7375 2525);
FORCEPROP 1 LAST VALUE 0
J 2
(-7400 2525);
DISPLAY 0.617021 (-7400 2525);
FORCEPROP 2 LAST CDS_LIB pure_quanta
J 0
(-7550 2525);
DISPLAY INVISIBLE (-7550 2525);
FORCEPROP 1 LAST WATTAGE 1/16W
J 2
(-7350 2475);
DISPLAY 0.617021 (-7350 2475);
DISPLAY INVISIBLE (-7350 2475);
FORCEPROP 2 LAST BOM_COST VR_SYSTEM 
J 0
(-7600 2675);
DISPLAY 0.680851 (-7600 2675);
DISPLAY INVISIBLE (-7600 2675);
FORCEPROP 1 LAST PATH I137
J 0
(-7600 2675);
DISPLAY 0.978723 (-7600 2675);
PAINT WHITE (-7600 2675);
DISPLAY INVISIBLE (-7600 2675);
FORCEPROP 1 LAST PART_NUMBER CS00002JB13
J 0
(-7700 2575);
DISPLAY 0.617021 (-7700 2575);
DISPLAY INVISIBLE (-7700 2575);
FORCEADD Q_RES..1
(-7575 2600);
FORCEPROP 1 LAST LOCATION R6313
J 0
(-7850 2600);
DISPLAY 0.808511 (-7850 2600);
FORCEPROP 0 LAST $SEC 1
J 0
(-7700 2700);
DISPLAY 0.680851 (-7700 2700);
PAINT MONO (-7700 2700);
DISPLAY INVISIBLE (-7700 2700);
FORCEPROP 0 LAST CDS_SEC 1
J 0
(-7700 2700);
DISPLAY 0.680851 (-7700 2700);
DISPLAY INVISIBLE (-7700 2700);
FORCEPROP 1 LASTPIN (-7675 2600) $PN 1
J 0
(-7663 2612);
DISPLAY 0.787234 (-7663 2612);
PAINT MONO (-7663 2612);
FORCEPROP 1 LASTPIN (-7475 2600) $PN 2
J 0
(-7513 2612);
DISPLAY 0.787234 (-7513 2612);
PAINT MONO (-7513 2612);
FORCEPROP 2 LAST ROOM USB3_HUB2_TI
J 0
(-7750 2675);
DISPLAY 0.553191 (-7750 2675);
PAINT RED (-7750 2675);
FORCEPROP 1 LAST VALUE 0
J 2
(-7425 2600);
DISPLAY 0.617021 (-7425 2600);
FORCEPROP 1 LAST PACK_TYPE 0402LF
J 0
(-7325 2600);
DISPLAY 0.617021 (-7325 2600);
FORCEPROP 1 LAST TOLERANCE 5%
J 0
(-7400 2600);
DISPLAY 0.617021 (-7400 2600);
FORCEPROP 1 LAST MATERIAL CHIP
J 0
(-7125 2600);
DISPLAY 0.617021 (-7125 2600);
FORCEPROP 2 LAST BOM_COST VR_SYSTEM 
J 0
(-7625 2750);
DISPLAY 0.680851 (-7625 2750);
DISPLAY INVISIBLE (-7625 2750);
FORCEPROP 1 LAST WATTAGE 1/16W
J 2
(-7375 2550);
DISPLAY 0.617021 (-7375 2550);
DISPLAY INVISIBLE (-7375 2550);
FORCEPROP 2 LAST CDS_LIB pure_quanta
J 0
(-7575 2600);
DISPLAY INVISIBLE (-7575 2600);
FORCEPROP 1 LAST PATH I138
J 0
(-7625 2750);
DISPLAY 0.978723 (-7625 2750);
PAINT WHITE (-7625 2750);
DISPLAY INVISIBLE (-7625 2750);
FORCEPROP 1 LAST PART_NUMBER CS00002JB13
J 0
(-7725 2650);
DISPLAY 0.617021 (-7725 2650);
DISPLAY INVISIBLE (-7725 2650);
FORCEADD UNIVERSAL_POWER..1
(-8750 3350);
FORCEPROP 3 LASTPIN (-8750 3300) SIG_NAME P3V3_AUX\g
J 0
(-8740 3310);
DISPLAY 0.659574 (-8740 3310);
PAINT MONO (-8740 3310);
DISPLAY INVISIBLE (-8740 3310);
FORCEPROP 1 LAST HDL_POWER P3V3_AUX
J 1
(-8750 3400);
DISPLAY 0.489362 (-8750 3400);
PAINT GREEN (-8750 3400);
FORCEPROP 2 LAST BOM_COST VR_SYSTEM
J 0
(-8750 3450);
DISPLAY 0.617021 (-8750 3450);
PAINT PURPLE (-8750 3450);
DISPLAY INVISIBLE (-8750 3450);
FORCEPROP 2 LAST CDS_LIB pure_quanta_power
J 0
(-8750 3350);
DISPLAY INVISIBLE (-8750 3350);
FORCEPROP 1 LAST PATH I139
J 0
(-8700 3375);
DISPLAY 0.872340 (-8700 3375);
PAINT AQUA (-8700 3375);
DISPLAY INVISIBLE (-8700 3375);
FORCEADD Q_RES..2
R 2
(-8750 2950);
FORCEPROP 1 LAST LOCATION R6315
J 2
(-8795 3075);
DISPLAY 0.638298 (-8795 3075);
FORCEPROP 0 LAST $SEC 1
J 0
(-8775 3125);
DISPLAY 0.680851 (-8775 3125);
PAINT MONO (-8775 3125);
DISPLAY INVISIBLE (-8775 3125);
FORCEPROP 0 LAST CDS_SEC 1
J 0
(-8775 3125);
DISPLAY 0.680851 (-8775 3125);
DISPLAY INVISIBLE (-8775 3125);
FORCEPROP 1 LASTPIN (-8750 3050) $PN 1
J 2
(-8755 3012);
DISPLAY 0.787234 (-8755 3012);
PAINT MONO (-8755 3012);
FORCEPROP 1 LASTPIN (-8750 2850) $PN 2
J 2
(-8755 2860);
DISPLAY 0.787234 (-8755 2860);
PAINT MONO (-8755 2860);
FORCEPROP 1 LAST WATTAGE 1/16W
J 2
(-8790 2925);
DISPLAY 0.510638 (-8790 2925);
FORCEPROP 1 LAST MATERIAL CHIP
J 2
(-8790 2875);
DISPLAY 0.510638 (-8790 2875);
FORCEPROP 1 LAST PACK_TYPE 0402LF
J 2
(-8775 2825);
DISPLAY 0.510638 (-8775 2825);
FORCEPROP 2 LAST ROOM USB3_HUB2_TI
J 0
(-9075 2775);
DISPLAY 0.553191 (-9075 2775);
PAINT RED (-9075 2775);
FORCEPROP 1 LAST TOLERANCE 1%
J 2
(-8795 2975);
DISPLAY 0.510638 (-8795 2975);
FORCEPROP 1 LAST VALUE 10K
J 2
(-8795 3025);
DISPLAY 0.510638 (-8795 3025);
FORCEPROP 2 LAST CDS_LIB pure_quanta
J 0
(-8750 2950);
DISPLAY INVISIBLE (-8750 2950);
FORCEPROP 1 LAST PATH I140
J 2
(-8800 3125);
DISPLAY 0.978723 (-8800 3125);
PAINT WHITE (-8800 3125);
DISPLAY INVISIBLE (-8800 3125);
FORCEPROP 1 LAST PART_NUMBER CS31002FB08
J 2
(-8790 2825);
DISPLAY 0.510638 (-8790 2825);
DISPLAY INVISIBLE (-8790 2825);
FORCEADD OFFPAGE..1
(-8750 2525);
FORCEPROP 2 LAST $XR2 176 
J 0
(-9002 2489);
DISPLAY 0.638298 (-9002 2489);
PAINT MONO (-9002 2489);
FORCEPROP 2 LAST $XR1 251 
J 0
(-9122 2525);
DISPLAY 0.638298 (-9122 2525);
PAINT MONO (-9122 2525);
FORCEPROP 2 LAST $XR0 179 
J 0
(-9002 2525);
DISPLAY 0.638298 (-9002 2525);
PAINT MONO (-9002 2525);
FORCEPROP 2 LAST CDS_LIB standard
J 2
(-8750 2525);
DISPLAY INVISIBLE (-8750 2525);
FORCEPROP 1 LAST OFFPAGE TRUE
J 0
(-8425 2400);
DISPLAY 0.872340 (-8425 2400);
PAINT GREEN (-8425 2400);
DISPLAY INVISIBLE (-8425 2400);
FORCEPROP 1 LAST COMMENT_BODY TRUE
J 0
(-8625 2425);
DISPLAY 0.872340 (-8625 2425);
PAINT GREEN (-8625 2425);
DISPLAY INVISIBLE (-8625 2425);
FORCEPROP 2 LAST PATH I141
J 2
(-8950 2575);
DISPLAY 0.680851 (-8950 2575);
DISPLAY INVISIBLE (-8950 2575);
FORCEADD OFFPAGE..3
(-3125 4300);
FORCEPROP 2 LAST $XR0 180 
J 0
(-2911 4300);
DISPLAY 0.638298 (-2911 4300);
PAINT MONO (-2911 4300);
FORCEPROP 2 LAST CDS_LIB standard
J 0
(-3125 4300);
DISPLAY INVISIBLE (-3125 4300);
FORCEPROP 1 LAST OFFPAGE TRUE
J 0
(-2800 4175);
DISPLAY 0.872340 (-2800 4175);
PAINT GREEN (-2800 4175);
DISPLAY INVISIBLE (-2800 4175);
FORCEPROP 1 LAST COMMENT_BODY TRUE
J 0
(-3175 4200);
DISPLAY 0.872340 (-3175 4200);
PAINT GREEN (-3175 4200);
DISPLAY INVISIBLE (-3175 4200);
FORCEPROP 2 LAST PATH I142
J 0
(-2900 4350);
DISPLAY 0.680851 (-2900 4350);
DISPLAY INVISIBLE (-2900 4350);
FORCEADD Q_RES..1
(-7200 3900);
FORCEPROP 1 LAST LOCATION R6270
J 0
(-7475 3900);
DISPLAY 0.808511 (-7475 3900);
FORCEPROP 0 LAST $SEC 1
J 0
(-7325 4000);
DISPLAY 0.680851 (-7325 4000);
PAINT MONO (-7325 4000);
DISPLAY INVISIBLE (-7325 4000);
FORCEPROP 0 LAST CDS_SEC 1
J 0
(-7325 4000);
DISPLAY 0.680851 (-7325 4000);
DISPLAY INVISIBLE (-7325 4000);
FORCEPROP 1 LASTPIN (-7300 3900) $PN 1
J 0
(-7288 3912);
DISPLAY 0.787234 (-7288 3912);
PAINT MONO (-7288 3912);
FORCEPROP 1 LASTPIN (-7100 3900) $PN 2
J 0
(-7138 3912);
DISPLAY 0.787234 (-7138 3912);
PAINT MONO (-7138 3912);
FORCEPROP 1 LAST VALUE 0
J 2
(-7050 3900);
DISPLAY 0.617021 (-7050 3900);
FORCEPROP 1 LAST TOLERANCE 5%
J 0
(-7025 3900);
DISPLAY 0.617021 (-7025 3900);
FORCEPROP 1 LAST MATERIAL CHIP
J 0
(-7100 3850);
DISPLAY 0.617021 (-7100 3850);
FORCEPROP 1 LAST PACK_TYPE 0402LF
J 0
(-7425 3850);
DISPLAY 0.617021 (-7425 3850);
FORCEPROP 2 LAST ROOM USB3_HUB2_MRP
J 0
(-7400 3800);
DISPLAY 0.553191 (-7400 3800);
PAINT RED (-7400 3800);
FORCEPROP 1 LAST WATTAGE 1/16W
J 2
(-7000 3850);
DISPLAY 0.617021 (-7000 3850);
DISPLAY INVISIBLE (-7000 3850);
FORCEPROP 2 LAST BOM_COST VR_SYSTEM 
J 0
(-7250 4050);
DISPLAY 0.680851 (-7250 4050);
DISPLAY INVISIBLE (-7250 4050);
FORCEPROP 2 LAST CDS_LIB pure_quanta
J 0
(-7200 3900);
DISPLAY INVISIBLE (-7200 3900);
FORCEPROP 1 LAST PATH I143
J 0
(-7250 4050);
DISPLAY 0.978723 (-7250 4050);
PAINT WHITE (-7250 4050);
DISPLAY INVISIBLE (-7250 4050);
FORCEPROP 1 LAST PART_NUMBER CS00002JB13
J 0
(-7350 3950);
DISPLAY 0.617021 (-7350 3950);
DISPLAY INVISIBLE (-7350 3950);
FORCEADD UNIVERSAL_POWER..1
(-7925 4125);
FORCEPROP 3 LASTPIN (-7925 4075) SIG_NAME P3V3_AUX_CPU0_USB2_AVDD33\g
J 0
(-7915 4085);
DISPLAY 0.659574 (-7915 4085);
PAINT MONO (-7915 4085);
DISPLAY INVISIBLE (-7915 4085);
FORCEPROP 1 LAST HDL_POWER P3V3_AUX_CPU0_USB2_AVDD33
J 1
(-7925 4175);
DISPLAY 0.489362 (-7925 4175);
PAINT GREEN (-7925 4175);
FORCEPROP 2 LAST BOM_COST VR_SYSTEM
J 0
(-7925 4225);
DISPLAY 0.617021 (-7925 4225);
PAINT PURPLE (-7925 4225);
DISPLAY INVISIBLE (-7925 4225);
FORCEPROP 2 LAST CDS_LIB pure_quanta_power
J 0
(-7925 4125);
DISPLAY INVISIBLE (-7925 4125);
FORCEPROP 1 LAST PATH I144
J 0
(-7875 4150);
DISPLAY 0.872340 (-7875 4150);
PAINT AQUA (-7875 4150);
DISPLAY INVISIBLE (-7875 4150);
FORCEADD Q_CAP..1
(-8175 3425);
FORCEPROP 1 LAST LOCATION C6089
J 0
(-8125 3475);
DISPLAY 0.638298 (-8125 3475);
FORCEPROP 0 LAST $SEC 1
J 0
(-8125 3525);
DISPLAY 0.680851 (-8125 3525);
PAINT MONO (-8125 3525);
DISPLAY INVISIBLE (-8125 3525);
FORCEPROP 0 LAST CDS_SEC 1
J 0
(-8125 3525);
DISPLAY 0.680851 (-8125 3525);
DISPLAY INVISIBLE (-8125 3525);
FORCEPROP 1 LASTPIN (-8175 3525) $PN 1
J 0
(-8165 3505);
DISPLAY 0.787234 (-8165 3505);
PAINT MONO (-8165 3505);
FORCEPROP 1 LASTPIN (-8175 3325) $PN 2
J 0
(-8165 3305);
DISPLAY 0.787234 (-8165 3305);
PAINT MONO (-8165 3305);
FORCEPROP 1 LAST PACK_TYPE C0402
J 0
(-8125 3225);
DISPLAY 0.638298 (-8125 3225);
FORCEPROP 1 LAST MATERIAL X6S
J 0
(-8125 3275);
DISPLAY 0.638298 (-8125 3275);
FORCEPROP 1 LAST VOLTAGE 25V
J 0
(-8125 3375);
DISPLAY 0.638298 (-8125 3375);
FORCEPROP 1 LAST TOLERANCE 10%
J 0
(-8125 3325);
DISPLAY 0.638298 (-8125 3325);
FORCEPROP 2 LAST ROOM USB3_HUB2_TI
J 0
(-8125 3175);
DISPLAY 0.680851 (-8125 3175);
PAINT RED (-8125 3175);
FORCEPROP 1 LAST VALUE 1UF
J 0
(-8125 3425);
DISPLAY 0.638298 (-8125 3425);
FORCEPROP 2 LAST CDS_LIB pure_quanta
J 0
(-8175 3425);
DISPLAY INVISIBLE (-8175 3425);
FORCEPROP 1 LAST PATH I145
J 0
(-8125 3575);
DISPLAY 0.978723 (-8125 3575);
PAINT WHITE (-8125 3575);
DISPLAY INVISIBLE (-8125 3575);
FORCEPROP 1 LAST PART_NUMBER CH5104KEB02
J 0
(-8125 3275);
DISPLAY 0.638298 (-8125 3275);
DISPLAY INVISIBLE (-8125 3275);
FORCEADD OFFPAGE..3
(-3050 3850);
FORCEPROP 2 LAST $XR0 180 
J 0
(-2836 3850);
DISPLAY 0.638298 (-2836 3850);
PAINT MONO (-2836 3850);
FORCEPROP 2 LAST CDS_LIB standard
J 0
(-3050 3850);
DISPLAY INVISIBLE (-3050 3850);
FORCEPROP 1 LAST OFFPAGE TRUE
J 0
(-2725 3725);
DISPLAY 0.872340 (-2725 3725);
PAINT GREEN (-2725 3725);
DISPLAY INVISIBLE (-2725 3725);
FORCEPROP 1 LAST COMMENT_BODY TRUE
J 0
(-3100 3750);
DISPLAY 0.872340 (-3100 3750);
PAINT GREEN (-3100 3750);
DISPLAY INVISIBLE (-3100 3750);
FORCEPROP 2 LAST PATH I146
J 0
(-2825 3900);
DISPLAY 0.680851 (-2825 3900);
DISPLAY INVISIBLE (-2825 3900);
FORCEADD OFFPAGE..3
(-3050 3900);
FORCEPROP 2 LAST $XR0 180 
J 0
(-2836 3900);
DISPLAY 0.638298 (-2836 3900);
PAINT MONO (-2836 3900);
FORCEPROP 2 LAST CDS_LIB standard
J 0
(-3050 3900);
DISPLAY INVISIBLE (-3050 3900);
FORCEPROP 1 LAST OFFPAGE TRUE
J 0
(-2725 3775);
DISPLAY 0.872340 (-2725 3775);
PAINT GREEN (-2725 3775);
DISPLAY INVISIBLE (-2725 3775);
FORCEPROP 1 LAST COMMENT_BODY TRUE
J 0
(-3100 3800);
DISPLAY 0.872340 (-3100 3800);
PAINT GREEN (-3100 3800);
DISPLAY INVISIBLE (-3100 3800);
FORCEPROP 2 LAST PATH I147
J 0
(-2825 3950);
DISPLAY 0.680851 (-2825 3950);
DISPLAY INVISIBLE (-2825 3950);
FORCEADD UNIVERSAL_POWER..1
(-1650 2150);
FORCEPROP 3 LASTPIN (-1650 2100) SIG_NAME P1V2_CPU0_USB2_DVDD12\g
J 0
(-1640 2110);
DISPLAY 0.659574 (-1640 2110);
PAINT MONO (-1640 2110);
DISPLAY INVISIBLE (-1640 2110);
FORCEPROP 1 LAST HDL_POWER P1V2_CPU0_USB2_DVDD12
J 1
(-1650 2200);
DISPLAY 0.617021 (-1650 2200);
PAINT GREEN (-1650 2200);
FORCEPROP 2 LAST BOM_COST VR_SYSTEM
J 0
(-1650 2250);
DISPLAY 0.617021 (-1650 2250);
PAINT PURPLE (-1650 2250);
DISPLAY INVISIBLE (-1650 2250);
FORCEPROP 2 LAST CDS_LIB pure_quanta_power
J 0
(-1650 2150);
DISPLAY INVISIBLE (-1650 2150);
FORCEPROP 1 LAST PATH I148
J 0
(-1600 2175);
DISPLAY 0.872340 (-1600 2175);
PAINT AQUA (-1600 2175);
DISPLAY INVISIBLE (-1600 2175);
FORCEADD Q_RES..1
(-2300 2050);
FORCEPROP 1 LAST LOCATION R6268
J 0
(-2575 2050);
DISPLAY 0.808511 (-2575 2050);
FORCEPROP 0 LAST $SEC 1
J 0
(-2425 2150);
DISPLAY 0.680851 (-2425 2150);
PAINT MONO (-2425 2150);
DISPLAY INVISIBLE (-2425 2150);
FORCEPROP 0 LAST CDS_SEC 1
J 0
(-2425 2150);
DISPLAY 0.680851 (-2425 2150);
DISPLAY INVISIBLE (-2425 2150);
FORCEPROP 1 LASTPIN (-2400 2050) $PN 1
J 0
(-2388 2062);
DISPLAY 0.787234 (-2388 2062);
PAINT MONO (-2388 2062);
FORCEPROP 1 LASTPIN (-2200 2050) $PN 2
J 0
(-2238 2062);
DISPLAY 0.787234 (-2238 2062);
PAINT MONO (-2238 2062);
FORCEPROP 1 LAST PACK_TYPE 0402LF
J 0
(-2050 2050);
DISPLAY 0.617021 (-2050 2050);
FORCEPROP 1 LAST TOLERANCE 5%
J 0
(-2125 2050);
DISPLAY 0.617021 (-2125 2050);
FORCEPROP 1 LAST MATERIAL CHIP
J 0
(-1850 2050);
DISPLAY 0.617021 (-1850 2050);
FORCEPROP 1 LAST VALUE 0
J 2
(-2150 2050);
DISPLAY 0.617021 (-2150 2050);
FORCEPROP 2 LAST ROOM USB3_HUB2_MRP
J 0
(-2425 2100);
DISPLAY 0.680851 (-2425 2100);
PAINT RED (-2425 2100);
FORCEPROP 2 LAST CDS_LIB pure_quanta
J 0
(-2300 2050);
DISPLAY INVISIBLE (-2300 2050);
FORCEPROP 1 LAST WATTAGE 1/16W
J 2
(-2100 2000);
DISPLAY 0.617021 (-2100 2000);
DISPLAY INVISIBLE (-2100 2000);
FORCEPROP 2 LAST BOM_COST VR_SYSTEM 
J 0
(-2350 2200);
DISPLAY 0.680851 (-2350 2200);
DISPLAY INVISIBLE (-2350 2200);
FORCEPROP 1 LAST PATH I149
J 0
(-2350 2200);
DISPLAY 0.978723 (-2350 2200);
PAINT WHITE (-2350 2200);
DISPLAY INVISIBLE (-2350 2200);
FORCEPROP 1 LAST PART_NUMBER CS00002JB13
J 0
(-2450 2100);
DISPLAY 0.617021 (-2450 2100);
DISPLAY INVISIBLE (-2450 2100);
FORCEADD UNIVERSAL_POWER..1
(-1300 3250);
FORCEPROP 3 LASTPIN (-1300 3200) SIG_NAME P3V3_AUX_CPU0_USB2_AVDD33\g
J 0
(-1290 3210);
DISPLAY 0.659574 (-1290 3210);
PAINT MONO (-1290 3210);
DISPLAY INVISIBLE (-1290 3210);
FORCEPROP 1 LAST HDL_POWER P3V3_AUX_CPU0_USB2_AVDD33
J 1
(-1300 3300);
DISPLAY 0.489362 (-1300 3300);
PAINT GREEN (-1300 3300);
FORCEPROP 2 LAST BOM_COST VR_SYSTEM
J 0
(-1300 3350);
DISPLAY 0.617021 (-1300 3350);
PAINT PURPLE (-1300 3350);
DISPLAY INVISIBLE (-1300 3350);
FORCEPROP 2 LAST CDS_LIB pure_quanta_power
J 0
(-1300 3250);
DISPLAY INVISIBLE (-1300 3250);
FORCEPROP 1 LAST PATH I150
J 0
(-1250 3275);
DISPLAY 0.872340 (-1250 3275);
PAINT AQUA (-1250 3275);
DISPLAY INVISIBLE (-1250 3275);
FORCEADD Q_RES..1
(-2450 3200);
FORCEPROP 1 LAST LOCATION R6264
J 0
(-2725 3200);
DISPLAY 0.808511 (-2725 3200);
FORCEPROP 0 LAST $SEC 1
J 0
(-2575 3300);
DISPLAY 0.680851 (-2575 3300);
PAINT MONO (-2575 3300);
DISPLAY INVISIBLE (-2575 3300);
FORCEPROP 0 LAST CDS_SEC 1
J 0
(-2575 3300);
DISPLAY 0.680851 (-2575 3300);
DISPLAY INVISIBLE (-2575 3300);
FORCEPROP 1 LASTPIN (-2550 3200) $PN 1
J 0
(-2538 3212);
DISPLAY 0.787234 (-2538 3212);
PAINT MONO (-2538 3212);
FORCEPROP 1 LASTPIN (-2350 3200) $PN 2
J 0
(-2388 3212);
DISPLAY 0.787234 (-2388 3212);
PAINT MONO (-2388 3212);
FORCEPROP 2 LAST ROOM USB3_HUB2_MRP
J 0
(-2600 3150);
DISPLAY 0.680851 (-2600 3150);
PAINT RED (-2600 3150);
FORCEPROP 1 LAST MATERIAL CHIP
J 0
(-2000 3200);
DISPLAY 0.617021 (-2000 3200);
FORCEPROP 1 LAST VALUE 0
J 2
(-2300 3200);
DISPLAY 0.617021 (-2300 3200);
FORCEPROP 1 LAST PACK_TYPE 0402LF
J 0
(-2200 3200);
DISPLAY 0.617021 (-2200 3200);
FORCEPROP 1 LAST TOLERANCE 5%
J 0
(-2275 3200);
DISPLAY 0.617021 (-2275 3200);
FORCEPROP 2 LAST CDS_LIB pure_quanta
J 0
(-2450 3200);
DISPLAY INVISIBLE (-2450 3200);
FORCEPROP 2 LAST BOM_COST VR_SYSTEM 
J 0
(-2500 3350);
DISPLAY 0.680851 (-2500 3350);
DISPLAY INVISIBLE (-2500 3350);
FORCEPROP 1 LAST WATTAGE 1/16W
J 2
(-2250 3150);
DISPLAY 0.617021 (-2250 3150);
DISPLAY INVISIBLE (-2250 3150);
FORCEPROP 1 LAST PATH I151
J 0
(-2500 3350);
DISPLAY 0.978723 (-2500 3350);
PAINT WHITE (-2500 3350);
DISPLAY INVISIBLE (-2500 3350);
FORCEPROP 1 LAST PART_NUMBER CS00002JB13
J 0
(-2600 3250);
DISPLAY 0.617021 (-2600 3250);
DISPLAY INVISIBLE (-2600 3250);
FORCEADD OFFPAGE..3
R 2
(-6550 5300);
FORCEPROP 2 LAST $XR0 180 
J 0
(-6830 5300);
DISPLAY 0.638298 (-6830 5300);
PAINT MONO (-6830 5300);
FORCEPROP 2 LAST CDS_LIB standard
J 2
(-6550 5300);
DISPLAY INVISIBLE (-6550 5300);
FORCEPROP 1 LAST OFFPAGE TRUE
J 2
(-6875 5175);
DISPLAY 0.872340 (-6875 5175);
PAINT GREEN (-6875 5175);
DISPLAY INVISIBLE (-6875 5175);
FORCEPROP 1 LAST COMMENT_BODY TRUE
J 2
(-6500 5200);
DISPLAY 0.872340 (-6500 5200);
PAINT GREEN (-6500 5200);
DISPLAY INVISIBLE (-6500 5200);
FORCEPROP 2 LAST PATH I152
J 2
(-6775 5350);
DISPLAY 0.680851 (-6775 5350);
DISPLAY INVISIBLE (-6775 5350);
FORCEADD OFFPAGE..3
R 2
(-6550 5350);
FORCEPROP 2 LAST $XR0 180 
J 0
(-6830 5350);
DISPLAY 0.638298 (-6830 5350);
PAINT MONO (-6830 5350);
FORCEPROP 2 LAST CDS_LIB standard
J 0
(-6550 5350);
DISPLAY INVISIBLE (-6550 5350);
FORCEPROP 1 LAST OFFPAGE TRUE
J 2
(-6875 5225);
DISPLAY 0.872340 (-6875 5225);
PAINT GREEN (-6875 5225);
DISPLAY INVISIBLE (-6875 5225);
FORCEPROP 1 LAST COMMENT_BODY TRUE
J 2
(-6500 5250);
DISPLAY 0.872340 (-6500 5250);
PAINT GREEN (-6500 5250);
DISPLAY INVISIBLE (-6500 5250);
FORCEPROP 2 LAST PATH I153
J 0
(-6500 5425);
DISPLAY 0.680851 (-6500 5425);
DISPLAY INVISIBLE (-6500 5425);
FORCEADD UNIVERSAL_POWER..1
(-1675 3325);
FORCEPROP 3 LASTPIN (-1675 3275) SIG_NAME P1V2_CPU0_USB2_DVDD12\g
J 0
(-1665 3285);
DISPLAY 0.659574 (-1665 3285);
PAINT MONO (-1665 3285);
DISPLAY INVISIBLE (-1665 3285);
FORCEPROP 1 LAST HDL_POWER P1V2_CPU0_USB2_DVDD12
J 1
(-1675 3375);
DISPLAY 0.617021 (-1675 3375);
PAINT GREEN (-1675 3375);
FORCEPROP 2 LAST BOM_COST VR_SYSTEM
J 0
(-1675 3425);
DISPLAY 0.617021 (-1675 3425);
PAINT PURPLE (-1675 3425);
DISPLAY INVISIBLE (-1675 3425);
FORCEPROP 2 LAST CDS_LIB pure_quanta_power
J 0
(-1675 3325);
DISPLAY INVISIBLE (-1675 3325);
FORCEPROP 1 LAST PATH I154
J 0
(-1625 3350);
DISPLAY 0.872340 (-1625 3350);
PAINT AQUA (-1625 3350);
DISPLAY INVISIBLE (-1625 3350);
FORCEADD Q_RES..1
(-2450 3250);
FORCEPROP 1 LAST LOCATION R6263
J 0
(-2725 3250);
DISPLAY 0.808511 (-2725 3250);
FORCEPROP 0 LAST $SEC 1
J 0
(-2575 3350);
DISPLAY 0.680851 (-2575 3350);
PAINT MONO (-2575 3350);
DISPLAY INVISIBLE (-2575 3350);
FORCEPROP 0 LAST CDS_SEC 1
J 0
(-2575 3350);
DISPLAY 0.680851 (-2575 3350);
DISPLAY INVISIBLE (-2575 3350);
FORCEPROP 1 LASTPIN (-2550 3250) $PN 1
J 0
(-2538 3262);
DISPLAY 0.787234 (-2538 3262);
PAINT MONO (-2538 3262);
FORCEPROP 1 LASTPIN (-2350 3250) $PN 2
J 0
(-2388 3262);
DISPLAY 0.787234 (-2388 3262);
PAINT MONO (-2388 3262);
FORCEPROP 1 LAST PACK_TYPE 0402LF
J 0
(-2200 3250);
DISPLAY 0.617021 (-2200 3250);
FORCEPROP 2 LAST ROOM USB3_HUB2_MRP
J 0
(-2650 3325);
DISPLAY 0.680851 (-2650 3325);
PAINT RED (-2650 3325);
FORCEPROP 1 LAST TOLERANCE 5%
J 0
(-2275 3250);
DISPLAY 0.617021 (-2275 3250);
FORCEPROP 1 LAST MATERIAL CHIP
J 0
(-2000 3250);
DISPLAY 0.617021 (-2000 3250);
FORCEPROP 1 LAST VALUE 0
J 2
(-2300 3250);
DISPLAY 0.617021 (-2300 3250);
FORCEPROP 2 LAST CDS_LIB pure_quanta
J 0
(-2450 3250);
DISPLAY INVISIBLE (-2450 3250);
FORCEPROP 1 LAST WATTAGE 1/16W
J 2
(-2250 3200);
DISPLAY 0.617021 (-2250 3200);
DISPLAY INVISIBLE (-2250 3200);
FORCEPROP 2 LAST BOM_COST VR_SYSTEM 
J 0
(-2500 3400);
DISPLAY 0.680851 (-2500 3400);
DISPLAY INVISIBLE (-2500 3400);
FORCEPROP 1 LAST PATH I155
J 0
(-2500 3400);
DISPLAY 0.978723 (-2500 3400);
PAINT WHITE (-2500 3400);
DISPLAY INVISIBLE (-2500 3400);
FORCEPROP 1 LAST PART_NUMBER CS00002JB13
J 0
(-2600 3300);
DISPLAY 0.617021 (-2600 3300);
DISPLAY INVISIBLE (-2600 3300);
FORCEADD OFFPAGE..2
R 2
(-6575 5100);
FORCEPROP 2 LAST $XR0 180 
J 0
(-6830 5100);
DISPLAY 0.638298 (-6830 5100);
PAINT MONO (-6830 5100);
FORCEPROP 2 LAST CDS_LIB standard
J 2
(-6575 5100);
DISPLAY INVISIBLE (-6575 5100);
FORCEPROP 1 LAST OFFPAGE TRUE
J 2
(-6900 4975);
DISPLAY 0.872340 (-6900 4975);
PAINT GREEN (-6900 4975);
DISPLAY INVISIBLE (-6900 4975);
FORCEPROP 1 LAST COMMENT_BODY TRUE
J 2
(-6530 5005);
DISPLAY 0.872340 (-6530 5005);
PAINT GREEN (-6530 5005);
DISPLAY INVISIBLE (-6530 5005);
FORCEPROP 2 LAST PATH I156
J 2
(-6775 5150);
DISPLAY 0.680851 (-6775 5150);
DISPLAY INVISIBLE (-6775 5150);
FORCEADD OFFPAGE..2
R 2
(-6575 5150);
FORCEPROP 2 LAST $XR0 180 
J 0
(-6830 5150);
DISPLAY 0.638298 (-6830 5150);
PAINT MONO (-6830 5150);
FORCEPROP 2 LAST CDS_LIB standard
J 0
(-6575 5150);
DISPLAY INVISIBLE (-6575 5150);
FORCEPROP 1 LAST OFFPAGE TRUE
J 2
(-6900 5025);
DISPLAY 0.872340 (-6900 5025);
PAINT GREEN (-6900 5025);
DISPLAY INVISIBLE (-6900 5025);
FORCEPROP 1 LAST COMMENT_BODY TRUE
J 2
(-6530 5055);
DISPLAY 0.872340 (-6530 5055);
PAINT GREEN (-6530 5055);
DISPLAY INVISIBLE (-6530 5055);
FORCEPROP 2 LAST PATH I157
J 0
(-6525 5225);
DISPLAY 0.680851 (-6525 5225);
DISPLAY INVISIBLE (-6525 5225);
FORCEADD OFFPAGE..1
R 2
(-3050 4050);
FORCEPROP 2 LAST $XR0 180 
J 0
(-2864 4050);
DISPLAY 0.638298 (-2864 4050);
PAINT MONO (-2864 4050);
FORCEPROP 2 LAST CDS_LIB standard
J 2
(-3050 4050);
DISPLAY INVISIBLE (-3050 4050);
FORCEPROP 1 LAST OFFPAGE TRUE
J 2
(-3375 3925);
DISPLAY 0.872340 (-3375 3925);
PAINT GREEN (-3375 3925);
DISPLAY INVISIBLE (-3375 3925);
FORCEPROP 1 LAST COMMENT_BODY TRUE
J 2
(-3175 3950);
DISPLAY 0.872340 (-3175 3950);
PAINT GREEN (-3175 3950);
DISPLAY INVISIBLE (-3175 3950);
FORCEPROP 2 LAST PATH I158
J 0
(-2850 4100);
DISPLAY 0.680851 (-2850 4100);
DISPLAY INVISIBLE (-2850 4100);
FORCEADD OFFPAGE..1
R 2
(-3050 4100);
FORCEPROP 2 LAST $XR0 180 
J 0
(-2864 4100);
DISPLAY 0.638298 (-2864 4100);
PAINT MONO (-2864 4100);
FORCEPROP 2 LAST CDS_LIB standard
J 0
(-3050 4100);
DISPLAY INVISIBLE (-3050 4100);
FORCEPROP 1 LAST OFFPAGE TRUE
J 2
(-3375 3975);
DISPLAY 0.872340 (-3375 3975);
PAINT GREEN (-3375 3975);
DISPLAY INVISIBLE (-3375 3975);
FORCEPROP 1 LAST COMMENT_BODY TRUE
J 2
(-3175 4000);
DISPLAY 0.872340 (-3175 4000);
PAINT GREEN (-3175 4000);
DISPLAY INVISIBLE (-3175 4000);
FORCEPROP 2 LAST PATH I159
J 0
(-2850 4150);
DISPLAY 0.680851 (-2850 4150);
DISPLAY INVISIBLE (-2850 4150);
FORCEADD UNIVERSAL_POWER..1
(-7575 4475);
FORCEPROP 3 LASTPIN (-7575 4425) SIG_NAME P1V2_CPU0_USB2_DVDD12\g
J 0
(-7565 4435);
DISPLAY 0.659574 (-7565 4435);
PAINT MONO (-7565 4435);
DISPLAY INVISIBLE (-7565 4435);
FORCEPROP 1 LAST HDL_POWER P1V2_CPU0_USB2_DVDD12
J 1
(-7575 4525);
DISPLAY 0.617021 (-7575 4525);
PAINT GREEN (-7575 4525);
FORCEPROP 2 LAST CDS_LIB pure_quanta_power
J 0
(-7575 4475);
DISPLAY INVISIBLE (-7575 4475);
FORCEPROP 2 LAST BOM_COST VR_SYSTEM
J 0
(-7575 4575);
DISPLAY 0.617021 (-7575 4575);
PAINT PURPLE (-7575 4575);
DISPLAY INVISIBLE (-7575 4575);
FORCEPROP 1 LAST PATH I163
J 0
(-7525 4500);
DISPLAY 0.872340 (-7525 4500);
PAINT AQUA (-7525 4500);
DISPLAY INVISIBLE (-7525 4500);
FORCEADD Q_RES..1
(-7075 4275);
FORCEPROP 1 LAST LOCATION R6258
J 0
(-7350 4275);
DISPLAY 0.808511 (-7350 4275);
FORCEPROP 0 LAST $SEC 1
J 0
(-7225 4450);
DISPLAY 0.680851 (-7225 4450);
PAINT MONO (-7225 4450);
DISPLAY INVISIBLE (-7225 4450);
FORCEPROP 0 LAST CDS_SEC 1
J 0
(-7225 4450);
DISPLAY 0.680851 (-7225 4450);
DISPLAY INVISIBLE (-7225 4450);
FORCEPROP 1 LASTPIN (-7175 4275) $PN 1
J 0
(-7163 4287);
DISPLAY 0.787234 (-7163 4287);
PAINT MONO (-7163 4287);
FORCEPROP 1 LASTPIN (-6975 4275) $PN 2
J 0
(-7013 4287);
DISPLAY 0.787234 (-7013 4287);
PAINT MONO (-7013 4287);
FORCEPROP 1 LAST PACK_TYPE 0402LF
J 0
(-6850 4275);
DISPLAY 0.638298 (-6850 4275);
FORCEPROP 1 LAST WATTAGE 1/16W
J 2
(-6700 4350);
DISPLAY 0.638298 (-6700 4350);
FORCEPROP 1 LAST VALUE 4.7K
J 2
(-6875 4275);
DISPLAY 0.638298 (-6875 4275);
FORCEPROP 2 LAST ROOM USB3_HUB2_TI
J 0
(-7400 4225);
DISPLAY 0.553191 (-7400 4225);
PAINT RED (-7400 4225);
FORCEPROP 1 LAST MATERIAL EMPTY
J 0
(-7225 4400);
DISPLAY 0.638298 (-7225 4400);
FORCEPROP 1 LAST TOLERANCE 5%
J 0
(-7300 4350);
DISPLAY 0.638298 (-7300 4350);
FORCEPROP 2 LAST CDS_LIB pure_quanta
J 0
(-7075 4275);
DISPLAY INVISIBLE (-7075 4275);
FORCEPROP 1 LAST PATH I164
J 0
(-7125 4425);
DISPLAY 0.978723 (-7125 4425);
PAINT WHITE (-7125 4425);
DISPLAY INVISIBLE (-7125 4425);
FORCEPROP 1 LAST PART_NUMBER CS24702JB10
J 0
(-7225 4350);
DISPLAY 0.638298 (-7225 4350);
DISPLAY INVISIBLE (-7225 4350);
FORCEADD UNIVERSAL_POWER..1
(-7400 4425);
FORCEPROP 3 LASTPIN (-7400 4375) SIG_NAME P3V3_AUX\g
J 0
(-7390 4385);
DISPLAY 0.659574 (-7390 4385);
PAINT MONO (-7390 4385);
DISPLAY INVISIBLE (-7390 4385);
FORCEPROP 1 LAST HDL_POWER P3V3_AUX
J 1
(-7400 4475);
DISPLAY 0.489362 (-7400 4475);
PAINT GREEN (-7400 4475);
FORCEPROP 2 LAST CDS_LIB pure_quanta_power
J 0
(-7400 4425);
DISPLAY INVISIBLE (-7400 4425);
FORCEPROP 2 LAST BOM_COST VR_SYSTEM
J 0
(-7400 4525);
DISPLAY 0.617021 (-7400 4525);
PAINT PURPLE (-7400 4525);
DISPLAY INVISIBLE (-7400 4525);
FORCEPROP 1 LAST PATH I165
J 0
(-7350 4450);
DISPLAY 0.872340 (-7350 4450);
PAINT AQUA (-7350 4450);
DISPLAY INVISIBLE (-7350 4450);
FORCEADD Q_RES..1
(-7050 4050);
FORCEPROP 1 LAST LOCATION R6259
J 0
(-7325 4050);
DISPLAY 0.808511 (-7325 4050);
FORCEPROP 0 LAST $SEC 1
J 0
(-7200 4150);
DISPLAY 0.680851 (-7200 4150);
PAINT MONO (-7200 4150);
DISPLAY INVISIBLE (-7200 4150);
FORCEPROP 0 LAST CDS_SEC 1
J 0
(-7200 4150);
DISPLAY 0.680851 (-7200 4150);
DISPLAY INVISIBLE (-7200 4150);
FORCEPROP 1 LASTPIN (-7150 4050) $PN 1
J 0
(-7138 4062);
DISPLAY 0.787234 (-7138 4062);
PAINT MONO (-7138 4062);
FORCEPROP 1 LASTPIN (-6950 4050) $PN 2
J 0
(-6988 4062);
DISPLAY 0.787234 (-6988 4062);
PAINT MONO (-6988 4062);
FORCEPROP 1 LAST TOLERANCE 5%
J 0
(-6875 4050);
DISPLAY 0.617021 (-6875 4050);
FORCEPROP 1 LAST MATERIAL CHIP
J 0
(-6950 4000);
DISPLAY 0.617021 (-6950 4000);
FORCEPROP 1 LAST VALUE 0
J 2
(-6900 4050);
DISPLAY 0.617021 (-6900 4050);
FORCEPROP 1 LAST PACK_TYPE 0402LF
J 0
(-7150 4000);
DISPLAY 0.617021 (-7150 4000);
FORCEPROP 2 LAST ROOM USB3_HUB2_MRP
J 0
(-7275 4125);
DISPLAY 0.553191 (-7275 4125);
PAINT RED (-7275 4125);
FORCEPROP 1 LAST WATTAGE 1/16W
J 2
(-6850 4000);
DISPLAY 0.617021 (-6850 4000);
DISPLAY INVISIBLE (-6850 4000);
FORCEPROP 2 LAST CDS_LIB pure_quanta
J 0
(-7050 4050);
DISPLAY INVISIBLE (-7050 4050);
FORCEPROP 2 LAST BOM_COST VR_SYSTEM 
J 0
(-7100 4200);
DISPLAY 0.680851 (-7100 4200);
DISPLAY INVISIBLE (-7100 4200);
FORCEPROP 1 LAST PATH I166
J 0
(-7100 4200);
DISPLAY 0.978723 (-7100 4200);
PAINT WHITE (-7100 4200);
DISPLAY INVISIBLE (-7100 4200);
FORCEPROP 1 LAST PART_NUMBER CS00002JB13
J 0
(-7200 4100);
DISPLAY 0.617021 (-7200 4100);
DISPLAY INVISIBLE (-7200 4100);
FORCEADD OFFPAGE..1
(-6575 4900);
FORCEPROP 2 LAST $XR0 180 
J 0
(-6857 4900);
DISPLAY 0.638298 (-6857 4900);
PAINT MONO (-6857 4900);
FORCEPROP 2 LAST CDS_LIB standard
J 0
(-6575 4900);
DISPLAY INVISIBLE (-6575 4900);
FORCEPROP 1 LAST OFFPAGE TRUE
J 0
(-6250 4775);
DISPLAY 0.872340 (-6250 4775);
PAINT GREEN (-6250 4775);
DISPLAY INVISIBLE (-6250 4775);
FORCEPROP 1 LAST COMMENT_BODY TRUE
J 0
(-6450 4800);
DISPLAY 0.872340 (-6450 4800);
PAINT GREEN (-6450 4800);
DISPLAY INVISIBLE (-6450 4800);
FORCEPROP 2 LAST PATH I167
J 0
(-6825 4950);
DISPLAY 0.680851 (-6825 4950);
DISPLAY INVISIBLE (-6825 4950);
FORCEADD OFFPAGE..1
(-6575 4950);
FORCEPROP 2 LAST $XR0 180 
J 0
(-6857 4950);
DISPLAY 0.638298 (-6857 4950);
PAINT MONO (-6857 4950);
FORCEPROP 2 LAST CDS_LIB standard
J 0
(-6575 4950);
DISPLAY INVISIBLE (-6575 4950);
FORCEPROP 1 LAST OFFPAGE TRUE
J 0
(-6250 4825);
DISPLAY 0.872340 (-6250 4825);
PAINT GREEN (-6250 4825);
DISPLAY INVISIBLE (-6250 4825);
FORCEPROP 1 LAST COMMENT_BODY TRUE
J 0
(-6450 4850);
DISPLAY 0.872340 (-6450 4850);
PAINT GREEN (-6450 4850);
DISPLAY INVISIBLE (-6450 4850);
FORCEPROP 2 LAST PATH I168
J 0
(-6825 5000);
DISPLAY 0.680851 (-6825 5000);
DISPLAY INVISIBLE (-6825 5000);
FORCEADD Q_RES..2
(-9075 2125);
FORCEPROP 1 LAST LOCATION R6303
J 0
(-9030 2200);
DISPLAY 0.638298 (-9030 2200);
FORCEPROP 0 LAST $SEC 1
J 0
(-9025 2250);
DISPLAY 0.680851 (-9025 2250);
PAINT MONO (-9025 2250);
DISPLAY INVISIBLE (-9025 2250);
FORCEPROP 0 LAST CDS_SEC 1
J 0
(-9025 2250);
DISPLAY 0.680851 (-9025 2250);
DISPLAY INVISIBLE (-9025 2250);
FORCEPROP 1 LASTPIN (-9075 2225) $PN 1
J 0
(-9070 2187);
DISPLAY 0.787234 (-9070 2187);
PAINT MONO (-9070 2187);
FORCEPROP 1 LASTPIN (-9075 2025) $PN 2
J 0
(-9070 2035);
DISPLAY 0.787234 (-9070 2035);
PAINT MONO (-9070 2035);
FORCEPROP 1 LAST TOLERANCE 1%
J 0
(-9030 2100);
DISPLAY 0.638298 (-9030 2100);
FORCEPROP 2 LAST ROOM USB3_HUB2_MRP
J 0
(-9375 2050);
DISPLAY 0.446809 (-9375 2050);
PAINT RED (-9375 2050);
FORCEPROP 1 LAST WATTAGE 1/16W
J 0
(-9035 2050);
DISPLAY 0.638298 (-9035 2050);
FORCEPROP 1 LAST PACK_TYPE 0402LF
J 0
(-9035 1950);
DISPLAY 0.638298 (-9035 1950);
FORCEPROP 1 LAST VALUE 200K
J 0
(-9030 2150);
DISPLAY 0.638298 (-9030 2150);
FORCEPROP 1 LAST MATERIAL EMPTY
J 0
(-9035 2000);
DISPLAY 0.638298 (-9035 2000);
FORCEPROP 2 LAST CDS_LIB pure_quanta
J 0
(-9075 2125);
DISPLAY INVISIBLE (-9075 2125);
FORCEPROP 1 LAST PATH I169
J 0
(-9025 2300);
DISPLAY 0.978723 (-9025 2300);
PAINT WHITE (-9025 2300);
DISPLAY INVISIBLE (-9025 2300);
FORCEPROP 1 LAST PART_NUMBER CS42002FB05
J 0
(-9035 2000);
DISPLAY 0.638298 (-9035 2000);
DISPLAY INVISIBLE (-9035 2000);
FORCEADD UNIVERSAL_POWER..1
(-9075 2350);
FORCEPROP 3 LASTPIN (-9075 2300) SIG_NAME P3V3_AUX\g
J 0
(-9065 2310);
DISPLAY 0.659574 (-9065 2310);
PAINT MONO (-9065 2310);
DISPLAY INVISIBLE (-9065 2310);
FORCEPROP 1 LAST HDL_POWER P3V3_AUX
J 1
(-9075 2400);
DISPLAY 0.489362 (-9075 2400);
PAINT GREEN (-9075 2400);
FORCEPROP 2 LAST BOM_COST VR_SYSTEM
J 0
(-9075 2450);
DISPLAY 0.617021 (-9075 2450);
PAINT PURPLE (-9075 2450);
DISPLAY INVISIBLE (-9075 2450);
FORCEPROP 2 LAST CDS_LIB pure_quanta_power
J 0
(-9075 2350);
DISPLAY INVISIBLE (-9075 2350);
FORCEPROP 1 LAST PATH I170
J 0
(-9025 2375);
DISPLAY 0.872340 (-9025 2375);
PAINT AQUA (-9025 2375);
DISPLAY INVISIBLE (-9025 2375);
FORCEADD Q_RES..2
(-9075 1650);
FORCEPROP 1 LAST LOCATION R6302
J 0
(-9025 1800);
DISPLAY 0.638298 (-9025 1800);
FORCEPROP 0 LAST $SEC 1
J 0
(-9025 1900);
DISPLAY 0.680851 (-9025 1900);
PAINT MONO (-9025 1900);
DISPLAY INVISIBLE (-9025 1900);
FORCEPROP 0 LAST CDS_SEC 1
J 0
(-9025 1900);
DISPLAY 0.680851 (-9025 1900);
DISPLAY INVISIBLE (-9025 1900);
FORCEPROP 1 LASTPIN (-9075 1750) $PN 1
J 0
(-9070 1712);
DISPLAY 0.787234 (-9070 1712);
PAINT MONO (-9070 1712);
FORCEPROP 1 LASTPIN (-9075 1550) $PN 2
J 0
(-9070 1560);
DISPLAY 0.787234 (-9070 1560);
PAINT MONO (-9070 1560);
FORCEPROP 2 LAST ROOM USB3_HUB2_MRP
J 0
(-9025 1850);
DISPLAY 0.680851 (-9025 1850);
PAINT RED (-9025 1850);
FORCEPROP 1 LAST PACK_TYPE 0402LF
J 0
(-9025 1500);
DISPLAY 0.510638 (-9025 1500);
FORCEPROP 1 LAST MATERIAL CHIP
J 0
(-9025 1600);
DISPLAY 0.510638 (-9025 1600);
FORCEPROP 1 LAST WATTAGE 1/16W
J 0
(-9025 1650);
DISPLAY 0.510638 (-9025 1650);
FORCEPROP 1 LAST TOLERANCE 1%
J 0
(-9025 1700);
DISPLAY 0.510638 (-9025 1700);
FORCEPROP 1 LAST VALUE 200K
J 0
(-9025 1750);
DISPLAY 0.510638 (-9025 1750);
FORCEPROP 2 LAST CDS_LIB pure_quanta
J 0
(-9075 1650);
DISPLAY INVISIBLE (-9075 1650);
FORCEPROP 1 LAST PATH I175
J 0
(-9025 1825);
DISPLAY 0.978723 (-9025 1825);
PAINT WHITE (-9025 1825);
DISPLAY INVISIBLE (-9025 1825);
FORCEPROP 1 LAST PART_NUMBER CS42002FB05
J 0
(-9025 1550);
DISPLAY 0.510638 (-9025 1550);
DISPLAY INVISIBLE (-9025 1550);
FORCEADD GND..1
(-9075 1475);
FORCEPROP 3 LASTPIN (-9075 1525) SIG_NAME GND\g
J 0
(-9065 1535);
DISPLAY 0.659574 (-9065 1535);
PAINT MONO (-9065 1535);
DISPLAY INVISIBLE (-9065 1535);
FORCEPROP 2 LAST CDS_LIB pure_quanta_power
J 0
(-9075 1475);
DISPLAY INVISIBLE (-9075 1475);
FORCEPROP 1 LAST SIZE 1B
J 0
(-9000 1425);
DISPLAY 1.170213 (-9000 1425);
PAINT AQUA (-9000 1425);
DISPLAY INVISIBLE (-9000 1425);
FORCEPROP 1 LAST HDL_POWER GND
J 0
(-9075 1625);
DISPLAY 1.170213 (-9075 1625);
PAINT GREEN (-9075 1625);
DISPLAY INVISIBLE (-9075 1625);
FORCEPROP 1 LAST PATH I176
J 0
(-9000 1475);
DISPLAY 0.872340 (-9000 1475);
PAINT AQUA (-9000 1475);
DISPLAY INVISIBLE (-9000 1475);
FORCEADD UNIVERSAL_POWER..1
(-9200 3300);
FORCEPROP 3 LASTPIN (-9200 3250) SIG_NAME P3V3_AUX\g
J 0
(-9190 3260);
DISPLAY 0.659574 (-9190 3260);
PAINT MONO (-9190 3260);
DISPLAY INVISIBLE (-9190 3260);
FORCEPROP 1 LAST HDL_POWER P3V3_AUX
J 1
(-9200 3350);
DISPLAY 0.489362 (-9200 3350);
PAINT GREEN (-9200 3350);
FORCEPROP 2 LAST CDS_LIB pure_quanta_power
J 0
(-9200 3300);
DISPLAY INVISIBLE (-9200 3300);
FORCEPROP 2 LAST BOM_COST VR_SYSTEM
J 0
(-9200 3400);
DISPLAY 0.617021 (-9200 3400);
PAINT PURPLE (-9200 3400);
DISPLAY INVISIBLE (-9200 3400);
FORCEPROP 1 LAST PATH I178
J 0
(-9150 3325);
DISPLAY 0.872340 (-9150 3325);
PAINT AQUA (-9150 3325);
DISPLAY INVISIBLE (-9150 3325);
FORCEADD Q_RES..2
R 2
(-9200 3075);
FORCEPROP 1 LAST LOCATION R6301
J 2
(-9245 3200);
DISPLAY 0.638298 (-9245 3200);
FORCEPROP 0 LAST $SEC 1
J 0
(-9225 3250);
DISPLAY 0.680851 (-9225 3250);
PAINT MONO (-9225 3250);
DISPLAY INVISIBLE (-9225 3250);
FORCEPROP 0 LAST CDS_SEC 1
J 0
(-9225 3250);
DISPLAY 0.680851 (-9225 3250);
DISPLAY INVISIBLE (-9225 3250);
FORCEPROP 1 LASTPIN (-9200 3175) $PN 1
J 2
(-9205 3137);
DISPLAY 0.787234 (-9205 3137);
PAINT MONO (-9205 3137);
FORCEPROP 1 LASTPIN (-9200 2975) $PN 2
J 2
(-9205 2985);
DISPLAY 0.787234 (-9205 2985);
PAINT MONO (-9205 2985);
FORCEPROP 1 LAST WATTAGE 1/16W
J 2
(-9240 3050);
DISPLAY 0.510638 (-9240 3050);
FORCEPROP 1 LAST MATERIAL CHIP
J 2
(-9240 3000);
DISPLAY 0.510638 (-9240 3000);
FORCEPROP 1 LAST VALUE 10K
J 2
(-9245 3150);
DISPLAY 0.510638 (-9245 3150);
FORCEPROP 1 LAST TOLERANCE 1%
J 2
(-9245 3100);
DISPLAY 0.510638 (-9245 3100);
FORCEPROP 1 LAST PACK_TYPE 0402LF
J 2
(-9225 2950);
DISPLAY 0.510638 (-9225 2950);
FORCEPROP 2 LAST ROOM USB3_HUB2_TI
J 0
(-9425 2925);
DISPLAY 0.361702 (-9425 2925);
PAINT RED (-9425 2925);
FORCEPROP 2 LAST CDS_LIB pure_quanta
J 0
(-9200 3075);
DISPLAY INVISIBLE (-9200 3075);
FORCEPROP 1 LAST PATH I179
J 2
(-9250 3250);
DISPLAY 0.978723 (-9250 3250);
PAINT WHITE (-9250 3250);
DISPLAY INVISIBLE (-9250 3250);
FORCEPROP 1 LAST PART_NUMBER CS31002FB08
J 2
(-9240 2950);
DISPLAY 0.510638 (-9240 2950);
DISPLAY INVISIBLE (-9240 2950);
FORCEADD Q_RES..1
(-6925 2450);
FORCEPROP 1 LAST LOCATION R6299
J 0
(-6800 2450);
DISPLAY 0.808511 (-6800 2450);
FORCEPROP 0 LAST $SEC 1
J 0
(-7050 2550);
DISPLAY 0.680851 (-7050 2550);
PAINT MONO (-7050 2550);
DISPLAY INVISIBLE (-7050 2550);
FORCEPROP 0 LAST CDS_SEC 1
J 0
(-7050 2550);
DISPLAY 0.680851 (-7050 2550);
DISPLAY INVISIBLE (-7050 2550);
FORCEPROP 1 LASTPIN (-7025 2450) $PN 1
J 0
(-7013 2462);
DISPLAY 0.787234 (-7013 2462);
PAINT MONO (-7013 2462);
FORCEPROP 1 LASTPIN (-6825 2450) $PN 2
J 0
(-6863 2462);
DISPLAY 0.787234 (-6863 2462);
PAINT MONO (-6863 2462);
FORCEPROP 2 LAST ROOM USB3_HUB2_TI
J 0
(-7100 2400);
DISPLAY 0.553191 (-7100 2400);
PAINT RED (-7100 2400);
FORCEPROP 1 LAST MATERIAL CHIP
J 0
(-7275 2400);
DISPLAY 0.617021 (-7275 2400);
FORCEPROP 1 LAST VALUE 0
J 2
(-6725 2400);
DISPLAY 0.617021 (-6725 2400);
FORCEPROP 1 LAST TOLERANCE 5%
J 0
(-6675 2400);
DISPLAY 0.617021 (-6675 2400);
FORCEPROP 1 LAST PACK_TYPE 0402LF
J 0
(-7200 2450);
DISPLAY 0.617021 (-7200 2450);
FORCEPROP 2 LAST CDS_LIB pure_quanta
J 0
(-6925 2450);
DISPLAY INVISIBLE (-6925 2450);
FORCEPROP 1 LAST WATTAGE 1/16W
J 2
(-6725 2400);
DISPLAY 0.617021 (-6725 2400);
DISPLAY INVISIBLE (-6725 2400);
FORCEPROP 2 LAST BOM_COST VR_SYSTEM 
J 0
(-6975 2600);
DISPLAY 0.680851 (-6975 2600);
DISPLAY INVISIBLE (-6975 2600);
FORCEPROP 1 LAST PATH I180
J 0
(-6975 2600);
DISPLAY 0.978723 (-6975 2600);
PAINT WHITE (-6975 2600);
DISPLAY INVISIBLE (-6975 2600);
FORCEPROP 1 LAST PART_NUMBER CS00002JB13
J 0
(-7075 2500);
DISPLAY 0.617021 (-7075 2500);
DISPLAY INVISIBLE (-7075 2500);
FORCEADD Q_RES..1
(-7000 2325);
FORCEPROP 1 LAST LOCATION R6300
J 0
(-6850 2325);
DISPLAY 0.808511 (-6850 2325);
FORCEPROP 0 LAST $SEC 1
J 0
(-6550 2375);
DISPLAY 0.680851 (-6550 2375);
PAINT MONO (-6550 2375);
DISPLAY INVISIBLE (-6550 2375);
FORCEPROP 0 LAST CDS_SEC 1
J 0
(-6550 2375);
DISPLAY 0.680851 (-6550 2375);
DISPLAY INVISIBLE (-6550 2375);
FORCEPROP 1 LASTPIN (-7100 2325) $PN 1
J 0
(-7088 2337);
DISPLAY 0.787234 (-7088 2337);
PAINT MONO (-7088 2337);
FORCEPROP 1 LASTPIN (-6900 2325) $PN 2
J 0
(-6938 2337);
DISPLAY 0.787234 (-6938 2337);
PAINT MONO (-6938 2337);
FORCEPROP 2 LAST ROOM USB3_HUB2_MRP
J 0
(-7125 2275);
DISPLAY 0.553191 (-7125 2275);
PAINT RED (-7125 2275);
FORCEPROP 1 LAST MATERIAL CHIP
J 0
(-7275 2275);
DISPLAY 0.617021 (-7275 2275);
FORCEPROP 1 LAST PACK_TYPE 0402LF
J 0
(-7250 2325);
DISPLAY 0.617021 (-7250 2325);
FORCEPROP 1 LAST TOLERANCE 5%
J 0
(-6675 2275);
DISPLAY 0.617021 (-6675 2275);
FORCEPROP 1 LAST VALUE 0
J 2
(-6725 2275);
DISPLAY 0.617021 (-6725 2275);
FORCEPROP 2 LAST BOM_COST VR_SYSTEM 
J 0
(-7050 2475);
DISPLAY 0.680851 (-7050 2475);
DISPLAY INVISIBLE (-7050 2475);
FORCEPROP 1 LAST WATTAGE 1/16W
J 2
(-6800 2275);
DISPLAY 0.617021 (-6800 2275);
DISPLAY INVISIBLE (-6800 2275);
FORCEPROP 2 LAST CDS_LIB pure_quanta
J 0
(-7000 2325);
DISPLAY INVISIBLE (-7000 2325);
FORCEPROP 1 LAST PATH I181
J 0
(-7050 2475);
DISPLAY 0.978723 (-7050 2475);
PAINT WHITE (-7050 2475);
DISPLAY INVISIBLE (-7050 2475);
FORCEPROP 1 LAST PART_NUMBER CS00002JB13
J 0
(-7150 2375);
DISPLAY 0.617021 (-7150 2375);
DISPLAY INVISIBLE (-7150 2375);
FORCEADD Q_RES..1
(-6500 1725);
FORCEPROP 1 LAST LOCATION R6295
J 0
(-6775 1725);
DISPLAY 0.808511 (-6775 1725);
FORCEPROP 0 LAST $SEC 1
J 0
(-6625 1825);
DISPLAY 0.680851 (-6625 1825);
PAINT MONO (-6625 1825);
DISPLAY INVISIBLE (-6625 1825);
FORCEPROP 0 LAST CDS_SEC 1
J 0
(-6625 1825);
DISPLAY 0.680851 (-6625 1825);
DISPLAY INVISIBLE (-6625 1825);
FORCEPROP 1 LASTPIN (-6600 1725) $PN 1
J 0
(-6588 1737);
DISPLAY 0.787234 (-6588 1737);
PAINT MONO (-6588 1737);
FORCEPROP 1 LASTPIN (-6400 1725) $PN 2
J 0
(-6438 1737);
DISPLAY 0.787234 (-6438 1737);
PAINT MONO (-6438 1737);
FORCEPROP 1 LAST VALUE 0
J 2
(-6350 1725);
DISPLAY 0.617021 (-6350 1725);
FORCEPROP 1 LAST TOLERANCE 5%
J 0
(-6325 1725);
DISPLAY 0.617021 (-6325 1725);
FORCEPROP 2 LAST ROOM USB3_HUB2_TI
J 0
(-6675 1800);
DISPLAY 0.553191 (-6675 1800);
PAINT RED (-6675 1800);
FORCEPROP 1 LAST PACK_TYPE 0402LF
J 0
(-6250 1725);
DISPLAY 0.617021 (-6250 1725);
FORCEPROP 1 LAST MATERIAL CHIP
J 0
(-6050 1725);
DISPLAY 0.617021 (-6050 1725);
FORCEPROP 2 LAST BOM_COST VR_SYSTEM 
J 0
(-6550 1875);
DISPLAY 0.680851 (-6550 1875);
DISPLAY INVISIBLE (-6550 1875);
FORCEPROP 1 LAST WATTAGE 1/16W
J 2
(-6300 1675);
DISPLAY 0.617021 (-6300 1675);
DISPLAY INVISIBLE (-6300 1675);
FORCEPROP 2 LAST CDS_LIB pure_quanta
J 0
(-6500 1725);
DISPLAY INVISIBLE (-6500 1725);
FORCEPROP 1 LAST PATH I182
J 0
(-6550 1875);
DISPLAY 0.978723 (-6550 1875);
PAINT WHITE (-6550 1875);
DISPLAY INVISIBLE (-6550 1875);
FORCEPROP 1 LAST PART_NUMBER CS00002JB13
J 0
(-6650 1775);
DISPLAY 0.617021 (-6650 1775);
DISPLAY INVISIBLE (-6650 1775);
FORCEADD Q_RES..1
(-6475 1600);
FORCEPROP 1 LAST LOCATION R6296
J 0
(-6775 1600);
DISPLAY 0.808511 (-6775 1600);
FORCEPROP 0 LAST $SEC 1
J 0
(-6025 1650);
DISPLAY 0.680851 (-6025 1650);
PAINT MONO (-6025 1650);
DISPLAY INVISIBLE (-6025 1650);
FORCEPROP 0 LAST CDS_SEC 1
J 0
(-6025 1650);
DISPLAY 0.680851 (-6025 1650);
DISPLAY INVISIBLE (-6025 1650);
FORCEPROP 1 LASTPIN (-6575 1600) $PN 1
J 0
(-6563 1612);
DISPLAY 0.787234 (-6563 1612);
PAINT MONO (-6563 1612);
FORCEPROP 1 LASTPIN (-6375 1600) $PN 2
J 0
(-6413 1612);
DISPLAY 0.787234 (-6413 1612);
PAINT MONO (-6413 1612);
FORCEPROP 1 LAST VALUE 0
J 2
(-6325 1600);
DISPLAY 0.617021 (-6325 1600);
FORCEPROP 1 LAST TOLERANCE 5%
J 0
(-6300 1600);
DISPLAY 0.617021 (-6300 1600);
FORCEPROP 1 LAST MATERIAL CHIP
J 0
(-6025 1600);
DISPLAY 0.617021 (-6025 1600);
FORCEPROP 2 LAST ROOM USB3_HUB2_MRP
J 0
(-6625 1550);
DISPLAY 0.553191 (-6625 1550);
PAINT RED (-6625 1550);
FORCEPROP 1 LAST PACK_TYPE 0402LF
J 0
(-6225 1600);
DISPLAY 0.617021 (-6225 1600);
FORCEPROP 2 LAST CDS_LIB pure_quanta
J 0
(-6475 1600);
DISPLAY INVISIBLE (-6475 1600);
FORCEPROP 2 LAST BOM_COST VR_SYSTEM 
J 0
(-6525 1750);
DISPLAY 0.680851 (-6525 1750);
DISPLAY INVISIBLE (-6525 1750);
FORCEPROP 1 LAST WATTAGE 1/16W
J 2
(-6275 1550);
DISPLAY 0.617021 (-6275 1550);
DISPLAY INVISIBLE (-6275 1550);
FORCEPROP 1 LAST PATH I183
J 0
(-6525 1750);
DISPLAY 0.978723 (-6525 1750);
PAINT WHITE (-6525 1750);
DISPLAY INVISIBLE (-6525 1750);
FORCEPROP 1 LAST PART_NUMBER CS00002JB13
J 0
(-6625 1650);
DISPLAY 0.617021 (-6625 1650);
DISPLAY INVISIBLE (-6625 1650);
FORCEADD UNIVERSAL_POWER..1
(-7575 2175);
FORCEPROP 3 LASTPIN (-7575 2125) SIG_NAME P3V3_AUX\g
J 0
(-7565 2135);
DISPLAY 0.659574 (-7565 2135);
PAINT MONO (-7565 2135);
DISPLAY INVISIBLE (-7565 2135);
FORCEPROP 1 LAST HDL_POWER P3V3_AUX
J 1
(-7575 2225);
DISPLAY 0.489362 (-7575 2225);
PAINT GREEN (-7575 2225);
FORCEPROP 2 LAST BOM_COST VR_SYSTEM
J 0
(-7575 2275);
DISPLAY 0.617021 (-7575 2275);
PAINT PURPLE (-7575 2275);
DISPLAY INVISIBLE (-7575 2275);
FORCEPROP 2 LAST CDS_LIB pure_quanta_power
J 0
(-7575 2175);
DISPLAY INVISIBLE (-7575 2175);
FORCEPROP 1 LAST PATH I184
J 0
(-7525 2200);
DISPLAY 0.872340 (-7525 2200);
PAINT AQUA (-7525 2200);
DISPLAY INVISIBLE (-7525 2200);
FORCEADD Q_RES..2
R 2
(-7575 1925);
FORCEPROP 1 LAST LOCATION R6297
J 2
(-7620 2050);
DISPLAY 0.638298 (-7620 2050);
FORCEPROP 0 LAST $SEC 1
J 0
(-7600 2100);
DISPLAY 0.680851 (-7600 2100);
PAINT MONO (-7600 2100);
DISPLAY INVISIBLE (-7600 2100);
FORCEPROP 0 LAST CDS_SEC 1
J 0
(-7600 2100);
DISPLAY 0.680851 (-7600 2100);
DISPLAY INVISIBLE (-7600 2100);
FORCEPROP 1 LASTPIN (-7575 2025) $PN 1
J 2
(-7580 1987);
DISPLAY 0.787234 (-7580 1987);
PAINT MONO (-7580 1987);
FORCEPROP 1 LASTPIN (-7575 1825) $PN 2
J 2
(-7580 1835);
DISPLAY 0.787234 (-7580 1835);
PAINT MONO (-7580 1835);
FORCEPROP 1 LAST PACK_TYPE 0402LF
J 2
(-7600 1800);
DISPLAY 0.510638 (-7600 1800);
FORCEPROP 1 LAST MATERIAL CHIP
J 2
(-7615 1850);
DISPLAY 0.510638 (-7615 1850);
FORCEPROP 1 LAST TOLERANCE 1%
J 2
(-7620 1950);
DISPLAY 0.510638 (-7620 1950);
FORCEPROP 1 LAST VALUE 10K
J 2
(-7620 2000);
DISPLAY 0.510638 (-7620 2000);
FORCEPROP 2 LAST ROOM USB3_HUB2_TI
J 0
(-7525 1950);
DISPLAY 0.553191 (-7525 1950);
PAINT RED (-7525 1950);
FORCEPROP 1 LAST WATTAGE 1/16W
J 2
(-7615 1900);
DISPLAY 0.510638 (-7615 1900);
FORCEPROP 2 LAST CDS_LIB pure_quanta
J 0
(-7575 1925);
DISPLAY INVISIBLE (-7575 1925);
FORCEPROP 1 LAST PATH I185
J 2
(-7625 2100);
DISPLAY 0.978723 (-7625 2100);
PAINT WHITE (-7625 2100);
DISPLAY INVISIBLE (-7625 2100);
FORCEPROP 1 LAST PART_NUMBER CS31002FB08
J 2
(-7615 1800);
DISPLAY 0.510638 (-7615 1800);
DISPLAY INVISIBLE (-7615 1800);
FORCEADD UNIVERSAL_POWER..1
(-8025 2175);
FORCEPROP 3 LASTPIN (-8025 2125) SIG_NAME P3V3_AUX\g
J 0
(-8015 2135);
DISPLAY 0.659574 (-8015 2135);
PAINT MONO (-8015 2135);
DISPLAY INVISIBLE (-8015 2135);
FORCEPROP 1 LAST HDL_POWER P3V3_AUX
J 1
(-8025 2225);
DISPLAY 0.489362 (-8025 2225);
PAINT GREEN (-8025 2225);
FORCEPROP 2 LAST BOM_COST VR_SYSTEM
J 0
(-8025 2275);
DISPLAY 0.617021 (-8025 2275);
PAINT PURPLE (-8025 2275);
DISPLAY INVISIBLE (-8025 2275);
FORCEPROP 2 LAST CDS_LIB pure_quanta_power
J 0
(-8025 2175);
DISPLAY INVISIBLE (-8025 2175);
FORCEPROP 1 LAST PATH I186
J 0
(-7975 2200);
DISPLAY 0.872340 (-7975 2200);
PAINT AQUA (-7975 2200);
DISPLAY INVISIBLE (-7975 2200);
FORCEADD Q_RES..2
(-8025 1925);
FORCEPROP 1 LAST LOCATION R6298
J 0
(-7980 2050);
DISPLAY 0.638298 (-7980 2050);
FORCEPROP 0 LAST $SEC 1
J 0
(-7975 2100);
DISPLAY 0.680851 (-7975 2100);
PAINT MONO (-7975 2100);
DISPLAY INVISIBLE (-7975 2100);
FORCEPROP 0 LAST CDS_SEC 1
J 0
(-7975 2100);
DISPLAY 0.680851 (-7975 2100);
DISPLAY INVISIBLE (-7975 2100);
FORCEPROP 1 LASTPIN (-8025 2025) $PN 1
J 0
(-8020 1987);
DISPLAY 0.787234 (-8020 1987);
PAINT MONO (-8020 1987);
FORCEPROP 1 LASTPIN (-8025 1825) $PN 2
J 0
(-8020 1835);
DISPLAY 0.787234 (-8020 1835);
PAINT MONO (-8020 1835);
FORCEPROP 2 LAST ROOM USB3_HUB2_MRP
J 0
(-8300 1975);
DISPLAY 0.446809 (-8300 1975);
PAINT RED (-8300 1975);
FORCEPROP 1 LAST WATTAGE 1/16W
J 0
(-7985 1900);
DISPLAY 0.510638 (-7985 1900);
FORCEPROP 1 LAST MATERIAL CHIP
J 0
(-7985 1850);
DISPLAY 0.510638 (-7985 1850);
FORCEPROP 1 LAST PACK_TYPE 0402LF
J 0
(-8000 1800);
DISPLAY 0.510638 (-8000 1800);
FORCEPROP 1 LAST TOLERANCE 1%
J 0
(-7980 1950);
DISPLAY 0.510638 (-7980 1950);
FORCEPROP 1 LAST VALUE 10K
J 0
(-7980 2000);
DISPLAY 0.510638 (-7980 2000);
FORCEPROP 2 LAST CDS_LIB pure_quanta
J 0
(-8025 1925);
DISPLAY INVISIBLE (-8025 1925);
FORCEPROP 1 LAST PATH I187
J 0
(-7975 2100);
DISPLAY 0.978723 (-7975 2100);
PAINT WHITE (-7975 2100);
DISPLAY INVISIBLE (-7975 2100);
FORCEPROP 1 LAST PART_NUMBER CS31002FB08
J 0
(-7985 1800);
DISPLAY 0.510638 (-7985 1800);
DISPLAY INVISIBLE (-7985 1800);
FORCEADD Q_RES..1
(-6200 800);
FORCEPROP 1 LAST LOCATION R6330
J 0
(-6500 800);
DISPLAY 0.978723 (-6500 800);
FORCEPROP 0 LAST $SEC 1
J 0
(-6275 900);
DISPLAY 0.680851 (-6275 900);
PAINT MONO (-6275 900);
DISPLAY INVISIBLE (-6275 900);
FORCEPROP 0 LAST CDS_SEC 1
J 0
(-6275 900);
DISPLAY 0.680851 (-6275 900);
DISPLAY INVISIBLE (-6275 900);
FORCEPROP 1 LASTPIN (-6300 800) $PN 1
J 0
(-6288 812);
DISPLAY 0.787234 (-6288 812);
PAINT MONO (-6288 812);
FORCEPROP 1 LASTPIN (-6100 800) $PN 2
J 0
(-6138 812);
DISPLAY 0.787234 (-6138 812);
PAINT MONO (-6138 812);
FORCEPROP 1 LAST TOLERANCE 1%
J 0
(-5925 750);
DISPLAY 0.787234 (-5925 750);
FORCEPROP 1 LAST PACK_TYPE 0402LF
J 0
(-6050 825);
DISPLAY 0.638298 (-6050 825);
FORCEPROP 1 LAST MATERIAL CHIP
J 0
(-6375 750);
DISPLAY 0.638298 (-6375 750);
FORCEPROP 1 LAST VALUE 4.7K
J 2
(-5975 750);
DISPLAY 0.787234 (-5975 750);
FORCEPROP 2 LAST ROOM USB3_HUB2_MRP
J 0
(-6375 875);
DISPLAY 0.553191 (-6375 875);
PAINT RED (-6375 875);
FORCEPROP 2 LAST CDS_LIB pure_quanta
J 0
(-6200 800);
DISPLAY INVISIBLE (-6200 800);
FORCEPROP 1 LAST WATTAGE 1/16W
J 2
(-6225 650);
DISPLAY 0.787234 (-6225 650);
DISPLAY INVISIBLE (-6225 650);
FORCEPROP 1 LAST PATH I188
J 0
(-6250 950);
DISPLAY 0.978723 (-6250 950);
PAINT WHITE (-6250 950);
DISPLAY INVISIBLE (-6250 950);
FORCEPROP 1 LAST PART_NUMBER CS24702FB06
J 0
(-6175 650);
DISPLAY 0.787234 (-6175 650);
DISPLAY INVISIBLE (-6175 650);
FORCEADD GND..1
(-6500 550);
FORCEPROP 3 LASTPIN (-6500 600) SIG_NAME GND\g
J 0
(-6490 610);
DISPLAY 0.659574 (-6490 610);
PAINT MONO (-6490 610);
DISPLAY INVISIBLE (-6490 610);
FORCEPROP 1 LAST SIZE 1B
J 0
(-6425 500);
DISPLAY 1.170213 (-6425 500);
PAINT AQUA (-6425 500);
DISPLAY INVISIBLE (-6425 500);
FORCEPROP 2 LAST CDS_LIB pure_quanta_power
J 0
(-6500 550);
DISPLAY INVISIBLE (-6500 550);
FORCEPROP 1 LAST HDL_POWER GND
J 0
(-6500 700);
DISPLAY 1.170213 (-6500 700);
PAINT GREEN (-6500 700);
DISPLAY INVISIBLE (-6500 700);
FORCEPROP 1 LAST PATH I189
J 0
(-6425 550);
DISPLAY 0.872340 (-6425 550);
PAINT AQUA (-6425 550);
DISPLAY INVISIBLE (-6425 550);
FORCEADD OFFPAGE..2
R 2
(-6925 1450);
FORCEPROP 2 LAST $XR0 178 
J 0
(-7210 1450);
DISPLAY 0.638298 (-7210 1450);
PAINT MONO (-7210 1450);
FORCEPROP 2 LAST CDS_LIB standard
J 0
(-6925 1450);
DISPLAY INVISIBLE (-6925 1450);
FORCEPROP 1 LAST OFFPAGE TRUE
J 2
(-7250 1325);
DISPLAY 0.872340 (-7250 1325);
PAINT GREEN (-7250 1325);
DISPLAY INVISIBLE (-7250 1325);
FORCEPROP 1 LAST COMMENT_BODY TRUE
J 2
(-6880 1355);
DISPLAY 0.872340 (-6880 1355);
PAINT GREEN (-6880 1355);
DISPLAY INVISIBLE (-6880 1355);
FORCEPROP 2 LAST PATH I190
J 0
(-6875 1525);
DISPLAY 0.680851 (-6875 1525);
DISPLAY INVISIBLE (-6875 1525);
FORCEADD OFFPAGE..1
R 2
(-4875 800);
FORCEPROP 2 LAST $XR0 178 
J 0
(-4689 800);
DISPLAY 0.638298 (-4689 800);
PAINT MONO (-4689 800);
FORCEPROP 2 LAST CDS_LIB standard
J 0
(-4875 800);
DISPLAY INVISIBLE (-4875 800);
FORCEPROP 1 LAST OFFPAGE TRUE
J 2
(-5200 675);
DISPLAY 0.872340 (-5200 675);
PAINT GREEN (-5200 675);
DISPLAY INVISIBLE (-5200 675);
FORCEPROP 1 LAST COMMENT_BODY TRUE
J 2
(-5000 700);
DISPLAY 0.872340 (-5000 700);
PAINT GREEN (-5000 700);
DISPLAY INVISIBLE (-5000 700);
FORCEPROP 2 LAST PATH I191
J 0
(-4700 875);
DISPLAY 0.680851 (-4700 875);
DISPLAY INVISIBLE (-4700 875);
FORCEADD Q_RES..1
(-7850 5100);
FORCEPROP 1 LAST LOCATION R6285
J 0
(-7925 5150);
DISPLAY 0.808511 (-7925 5150);
FORCEPROP 0 LAST $SEC 1
J 0
(-7975 5200);
DISPLAY 0.680851 (-7975 5200);
PAINT MONO (-7975 5200);
DISPLAY INVISIBLE (-7975 5200);
FORCEPROP 0 LAST CDS_SEC 1
J 0
(-7975 5200);
DISPLAY 0.680851 (-7975 5200);
DISPLAY INVISIBLE (-7975 5200);
FORCEPROP 1 LASTPIN (-7950 5100) $PN 1
J 0
(-7938 5112);
DISPLAY 0.787234 (-7938 5112);
PAINT MONO (-7938 5112);
FORCEPROP 1 LASTPIN (-7750 5100) $PN 2
J 0
(-7788 5112);
DISPLAY 0.787234 (-7788 5112);
PAINT MONO (-7788 5112);
FORCEPROP 1 LAST TOLERANCE 5%
J 0
(-7675 5100);
DISPLAY 0.617021 (-7675 5100);
FORCEPROP 1 LAST PACK_TYPE 0402LF
J 0
(-7600 5100);
DISPLAY 0.617021 (-7600 5100);
FORCEPROP 1 LAST MATERIAL CHIP
J 0
(-7400 5100);
DISPLAY 0.617021 (-7400 5100);
FORCEPROP 1 LAST VALUE 0
J 2
(-7700 5100);
DISPLAY 0.617021 (-7700 5100);
FORCEPROP 2 LAST ROOM USB3_HUB2_TI
J 0
(-7950 5050);
DISPLAY 0.553191 (-7950 5050);
PAINT RED (-7950 5050);
FORCEPROP 2 LAST CDS_LIB pure_quanta
J 0
(-7850 5100);
DISPLAY INVISIBLE (-7850 5100);
FORCEPROP 1 LAST WATTAGE 1/16W
J 2
(-7650 5050);
DISPLAY 0.617021 (-7650 5050);
DISPLAY INVISIBLE (-7650 5050);
FORCEPROP 2 LAST BOM_COST VR_SYSTEM 
J 0
(-7900 5250);
DISPLAY 0.680851 (-7900 5250);
DISPLAY INVISIBLE (-7900 5250);
FORCEPROP 1 LAST PATH I192
J 0
(-7900 5250);
DISPLAY 0.978723 (-7900 5250);
PAINT WHITE (-7900 5250);
DISPLAY INVISIBLE (-7900 5250);
FORCEPROP 1 LAST PART_NUMBER CS00002JB13
J 0
(-8000 5150);
DISPLAY 0.617021 (-8000 5150);
DISPLAY INVISIBLE (-8000 5150);
FORCEADD Q_RES..1
(-7825 4625);
FORCEPROP 1 LAST LOCATION R6286
J 0
(-8100 4625);
DISPLAY 0.808511 (-8100 4625);
FORCEPROP 0 LAST $SEC 1
J 0
(-7375 4675);
DISPLAY 0.680851 (-7375 4675);
PAINT MONO (-7375 4675);
DISPLAY INVISIBLE (-7375 4675);
FORCEPROP 0 LAST CDS_SEC 1
J 0
(-7375 4675);
DISPLAY 0.680851 (-7375 4675);
DISPLAY INVISIBLE (-7375 4675);
FORCEPROP 1 LASTPIN (-7925 4625) $PN 1
J 0
(-7913 4637);
DISPLAY 0.787234 (-7913 4637);
PAINT MONO (-7913 4637);
FORCEPROP 1 LASTPIN (-7725 4625) $PN 2
J 0
(-7763 4637);
DISPLAY 0.787234 (-7763 4637);
PAINT MONO (-7763 4637);
FORCEPROP 1 LAST MATERIAL CHIP
J 0
(-7375 4625);
DISPLAY 0.617021 (-7375 4625);
FORCEPROP 1 LAST VALUE 0
J 2
(-7675 4625);
DISPLAY 0.617021 (-7675 4625);
FORCEPROP 1 LAST TOLERANCE 5%
J 0
(-7650 4625);
DISPLAY 0.617021 (-7650 4625);
FORCEPROP 2 LAST ROOM USB3_HUB2_MRP
J 0
(-7950 4575);
DISPLAY 0.553191 (-7950 4575);
PAINT RED (-7950 4575);
FORCEPROP 1 LAST PACK_TYPE 0402LF
J 0
(-7575 4625);
DISPLAY 0.617021 (-7575 4625);
FORCEPROP 2 LAST CDS_LIB pure_quanta
J 0
(-7825 4625);
DISPLAY INVISIBLE (-7825 4625);
FORCEPROP 1 LAST WATTAGE 1/16W
J 2
(-7625 4575);
DISPLAY 0.617021 (-7625 4575);
DISPLAY INVISIBLE (-7625 4575);
FORCEPROP 2 LAST BOM_COST VR_SYSTEM 
J 0
(-7875 4775);
DISPLAY 0.680851 (-7875 4775);
DISPLAY INVISIBLE (-7875 4775);
FORCEPROP 1 LAST PATH I193
J 0
(-7875 4775);
DISPLAY 0.978723 (-7875 4775);
PAINT WHITE (-7875 4775);
DISPLAY INVISIBLE (-7875 4775);
FORCEPROP 1 LAST PART_NUMBER CS00002JB13
J 0
(-7975 4675);
DISPLAY 0.617021 (-7975 4675);
DISPLAY INVISIBLE (-7975 4675);
FORCEADD UNIVERSAL_POWER..1
(-9175 5050);
FORCEPROP 3 LASTPIN (-9175 5000) SIG_NAME P3V3_AUX\g
J 0
(-9165 5010);
DISPLAY 0.659574 (-9165 5010);
PAINT MONO (-9165 5010);
DISPLAY INVISIBLE (-9165 5010);
FORCEPROP 1 LAST HDL_POWER P3V3_AUX
J 1
(-9175 5100);
DISPLAY 0.489362 (-9175 5100);
PAINT GREEN (-9175 5100);
FORCEPROP 2 LAST CDS_LIB pure_quanta_power
J 0
(-9175 5050);
DISPLAY INVISIBLE (-9175 5050);
FORCEPROP 2 LAST BOM_COST VR_SYSTEM
J 0
(-9175 5150);
DISPLAY 0.617021 (-9175 5150);
PAINT PURPLE (-9175 5150);
DISPLAY INVISIBLE (-9175 5150);
FORCEPROP 1 LAST PATH I194
J 0
(-9125 5075);
DISPLAY 0.872340 (-9125 5075);
PAINT AQUA (-9125 5075);
DISPLAY INVISIBLE (-9125 5075);
FORCEADD Q_RES..2
R 2
(-9175 4850);
FORCEPROP 1 LAST LOCATION R6289
J 2
(-9225 4875);
DISPLAY 0.638298 (-9225 4875);
FORCEPROP 0 LAST $SEC 1
J 0
(-9200 5025);
DISPLAY 0.680851 (-9200 5025);
PAINT MONO (-9200 5025);
DISPLAY INVISIBLE (-9200 5025);
FORCEPROP 0 LAST CDS_SEC 1
J 0
(-9200 5025);
DISPLAY 0.680851 (-9200 5025);
DISPLAY INVISIBLE (-9200 5025);
FORCEPROP 1 LASTPIN (-9175 4950) $PN 1
J 2
(-9180 4912);
DISPLAY 0.787234 (-9180 4912);
PAINT MONO (-9180 4912);
FORCEPROP 1 LASTPIN (-9175 4750) $PN 2
J 2
(-9180 4760);
DISPLAY 0.787234 (-9180 4760);
PAINT MONO (-9180 4760);
FORCEPROP 1 LAST WATTAGE 1/16W
J 2
(-9225 4725);
DISPLAY 0.510638 (-9225 4725);
FORCEPROP 1 LAST PACK_TYPE 0402LF
J 2
(-9200 4625);
DISPLAY 0.510638 (-9200 4625);
FORCEPROP 1 LAST VALUE 10K
J 2
(-9225 4825);
DISPLAY 0.510638 (-9225 4825);
FORCEPROP 1 LAST TOLERANCE 1%
J 2
(-9225 4775);
DISPLAY 0.510638 (-9225 4775);
FORCEPROP 1 LAST MATERIAL CHIP
J 2
(-9200 4675);
DISPLAY 0.510638 (-9200 4675);
FORCEPROP 2 LAST ROOM USB3_HUB2_MRP
J 0
(-9375 4550);
DISPLAY 0.553191 (-9375 4550);
PAINT RED (-9375 4550);
FORCEPROP 2 LAST CDS_LIB pure_quanta
J 0
(-9175 4850);
DISPLAY INVISIBLE (-9175 4850);
FORCEPROP 1 LAST PATH I195
J 2
(-9225 5025);
DISPLAY 0.978723 (-9225 5025);
PAINT WHITE (-9225 5025);
DISPLAY INVISIBLE (-9225 5025);
FORCEPROP 1 LAST PART_NUMBER CS31002FB08
J 2
(-9215 4725);
DISPLAY 0.510638 (-9215 4725);
DISPLAY INVISIBLE (-9215 4725);
FORCEADD UNIVERSAL_POWER..1
(-8675 5450);
FORCEPROP 3 LASTPIN (-8675 5400) SIG_NAME P3V3_AUX\g
J 0
(-8665 5410);
DISPLAY 0.659574 (-8665 5410);
PAINT MONO (-8665 5410);
DISPLAY INVISIBLE (-8665 5410);
FORCEPROP 1 LAST HDL_POWER P3V3_AUX
J 1
(-8675 5500);
DISPLAY 0.489362 (-8675 5500);
PAINT GREEN (-8675 5500);
FORCEPROP 2 LAST BOM_COST VR_SYSTEM
J 0
(-8675 5550);
DISPLAY 0.617021 (-8675 5550);
PAINT PURPLE (-8675 5550);
DISPLAY INVISIBLE (-8675 5550);
FORCEPROP 2 LAST CDS_LIB pure_quanta_power
J 0
(-8675 5450);
DISPLAY INVISIBLE (-8675 5450);
FORCEPROP 1 LAST PATH I196
J 0
(-8625 5475);
DISPLAY 0.872340 (-8625 5475);
PAINT AQUA (-8625 5475);
DISPLAY INVISIBLE (-8625 5475);
FORCEADD Q_RES..2
(-8675 5250);
FORCEPROP 1 LAST LOCATION R6287
J 0
(-8875 5300);
DISPLAY 0.808511 (-8875 5300);
FORCEPROP 0 LAST $SEC 1
J 0
(-8650 5375);
DISPLAY 0.680851 (-8650 5375);
PAINT MONO (-8650 5375);
DISPLAY INVISIBLE (-8650 5375);
FORCEPROP 0 LAST CDS_SEC 1
J 0
(-8650 5375);
DISPLAY 0.680851 (-8650 5375);
DISPLAY INVISIBLE (-8650 5375);
FORCEPROP 1 LASTPIN (-8675 5350) $PN 1
J 0
(-8670 5312);
DISPLAY 0.787234 (-8670 5312);
PAINT MONO (-8670 5312);
FORCEPROP 1 LASTPIN (-8675 5150) $PN 2
J 0
(-8670 5160);
DISPLAY 0.787234 (-8670 5160);
PAINT MONO (-8670 5160);
FORCEPROP 1 LAST PACK_TYPE 0402LF
J 0
(-8850 5175);
DISPLAY 0.510638 (-8850 5175);
FORCEPROP 1 LAST MATERIAL CHIP
J 0
(-8650 5125);
DISPLAY 0.510638 (-8650 5125);
FORCEPROP 1 LAST TOLERANCE 1%
J 0
(-8645 5225);
DISPLAY 0.510638 (-8645 5225);
FORCEPROP 1 LAST WATTAGE 1/16W
J 0
(-8650 5175);
DISPLAY 0.510638 (-8650 5175);
FORCEPROP 1 LAST VALUE 1K
J 0
(-8645 5275);
DISPLAY 0.510638 (-8645 5275);
FORCEPROP 2 LAST ROOM USB3_HUB2_TI
J 0
(-8950 5225);
DISPLAY 0.446809 (-8950 5225);
PAINT RED (-8950 5225);
FORCEPROP 2 LAST CDS_LIB pure_quanta
J 0
(-8675 5250);
DISPLAY INVISIBLE (-8675 5250);
FORCEPROP 1 LAST PATH I197
J 0
(-8625 5425);
DISPLAY 0.978723 (-8625 5425);
PAINT WHITE (-8625 5425);
DISPLAY INVISIBLE (-8625 5425);
FORCEPROP 1 LAST PART_NUMBER CS21002FB06
J 0
(-8650 5075);
DISPLAY 0.510638 (-8650 5075);
DISPLAY INVISIBLE (-8650 5075);
FORCEADD Q_RES..2
(-8675 4975);
FORCEPROP 1 LAST LOCATION R6288
J 0
(-8850 5050);
DISPLAY 0.808511 (-8850 5050);
FORCEPROP 0 LAST $SEC 1
J 0
(-8625 5150);
DISPLAY 0.680851 (-8625 5150);
PAINT MONO (-8625 5150);
DISPLAY INVISIBLE (-8625 5150);
FORCEPROP 0 LAST CDS_SEC 1
J 0
(-8625 5150);
DISPLAY 0.680851 (-8625 5150);
DISPLAY INVISIBLE (-8625 5150);
FORCEPROP 1 LASTPIN (-8675 5075) $PN 1
J 0
(-8670 5037);
DISPLAY 0.787234 (-8670 5037);
PAINT MONO (-8670 5037);
FORCEPROP 1 LASTPIN (-8675 4875) $PN 2
J 0
(-8670 4885);
DISPLAY 0.787234 (-8670 4885);
PAINT MONO (-8670 4885);
FORCEPROP 1 LAST MATERIAL EMPTY
J 0
(-8635 4900);
DISPLAY 0.638298 (-8635 4900);
FORCEPROP 1 LAST WATTAGE 1/16W
J 0
(-8635 4950);
DISPLAY 0.638298 (-8635 4950);
FORCEPROP 2 LAST ROOM USB3_HUB2_TI
J 0
(-9000 4975);
DISPLAY 0.553191 (-9000 4975);
PAINT RED (-9000 4975);
FORCEPROP 1 LAST TOLERANCE 1%
J 0
(-8630 5000);
DISPLAY 0.638298 (-8630 5000);
FORCEPROP 1 LAST PACK_TYPE 0402LF
J 0
(-8900 4900);
DISPLAY 0.638298 (-8900 4900);
FORCEPROP 1 LAST VALUE 1K
J 0
(-8630 5050);
DISPLAY 0.638298 (-8630 5050);
FORCEPROP 2 LAST CDS_LIB pure_quanta
J 0
(-8675 4975);
DISPLAY INVISIBLE (-8675 4975);
FORCEPROP 1 LAST PATH I198
J 0
(-8625 5150);
DISPLAY 0.978723 (-8625 5150);
PAINT WHITE (-8625 5150);
DISPLAY INVISIBLE (-8625 5150);
FORCEPROP 1 LAST PART_NUMBER CS21002FB06
J 0
(-8635 4850);
DISPLAY 0.638298 (-8635 4850);
DISPLAY INVISIBLE (-8635 4850);
FORCEADD GND..1
(-8675 4775);
FORCEPROP 3 LASTPIN (-8675 4825) SIG_NAME GND\g
J 0
(-8665 4835);
DISPLAY 0.659574 (-8665 4835);
PAINT MONO (-8665 4835);
DISPLAY INVISIBLE (-8665 4835);
FORCEPROP 1 LAST SIZE 1B
J 0
(-8600 4725);
DISPLAY 1.170213 (-8600 4725);
PAINT AQUA (-8600 4725);
DISPLAY INVISIBLE (-8600 4725);
FORCEPROP 2 LAST CDS_LIB pure_quanta_power
J 0
(-8675 4775);
DISPLAY INVISIBLE (-8675 4775);
FORCEPROP 1 LAST HDL_POWER GND
J 0
(-8675 4925);
DISPLAY 1.170213 (-8675 4925);
PAINT GREEN (-8675 4925);
DISPLAY INVISIBLE (-8675 4925);
FORCEPROP 1 LAST PATH I199
J 0
(-8600 4775);
DISPLAY 0.872340 (-8600 4775);
PAINT AQUA (-8600 4775);
DISPLAY INVISIBLE (-8600 4775);
FORCEADD Q_RES..1
(-6925 2750);
FORCEPROP 1 LAST LOCATION R6311
J 0
(-7200 2750);
DISPLAY 0.808511 (-7200 2750);
FORCEPROP 0 LAST $SEC 1
J 0
(-6475 2800);
DISPLAY 0.680851 (-6475 2800);
PAINT MONO (-6475 2800);
DISPLAY INVISIBLE (-6475 2800);
FORCEPROP 0 LAST CDS_SEC 1
J 0
(-6475 2800);
DISPLAY 0.680851 (-6475 2800);
DISPLAY INVISIBLE (-6475 2800);
FORCEPROP 1 LASTPIN (-7025 2750) $PN 1
J 0
(-7013 2762);
DISPLAY 0.787234 (-7013 2762);
PAINT MONO (-7013 2762);
FORCEPROP 1 LASTPIN (-6825 2750) $PN 2
J 0
(-6863 2762);
DISPLAY 0.787234 (-6863 2762);
PAINT MONO (-6863 2762);
FORCEPROP 1 LAST PACK_TYPE 0402LF
J 0
(-7150 2700);
DISPLAY 0.617021 (-7150 2700);
FORCEPROP 2 LAST ROOM USB3_HUB2_MRP
J 0
(-7075 2825);
DISPLAY 0.553191 (-7075 2825);
PAINT RED (-7075 2825);
FORCEPROP 1 LAST VALUE 0
J 2
(-6775 2750);
DISPLAY 0.617021 (-6775 2750);
FORCEPROP 1 LAST TOLERANCE 5%
J 0
(-6750 2750);
DISPLAY 0.617021 (-6750 2750);
FORCEPROP 1 LAST MATERIAL CHIP
J 0
(-6800 2700);
DISPLAY 0.617021 (-6800 2700);
FORCEPROP 2 LAST CDS_LIB pure_quanta
J 0
(-6925 2750);
DISPLAY INVISIBLE (-6925 2750);
FORCEPROP 2 LAST BOM_COST VR_SYSTEM 
J 0
(-6975 2900);
DISPLAY 0.680851 (-6975 2900);
DISPLAY INVISIBLE (-6975 2900);
FORCEPROP 1 LAST WATTAGE 1/16W
J 2
(-6725 2700);
DISPLAY 0.617021 (-6725 2700);
DISPLAY INVISIBLE (-6725 2700);
FORCEPROP 1 LAST PATH I200
J 0
(-6975 2900);
DISPLAY 0.978723 (-6975 2900);
PAINT WHITE (-6975 2900);
DISPLAY INVISIBLE (-6975 2900);
FORCEPROP 1 LAST PART_NUMBER CS00002JB13
J 0
(-7075 2800);
DISPLAY 0.617021 (-7075 2800);
DISPLAY INVISIBLE (-7075 2800);
FORCEADD OFFPAGE..3
R 2
(-8000 2750);
FORCEPROP 2 LAST $XR2 251 
J 0
(-8520 2750);
DISPLAY 0.638298 (-8520 2750);
PAINT MONO (-8520 2750);
FORCEPROP 2 LAST $XR1 179 
J 0
(-8400 2750);
DISPLAY 0.638298 (-8400 2750);
PAINT MONO (-8400 2750);
FORCEPROP 2 LAST $XR0 176 
J 0
(-8280 2750);
DISPLAY 0.638298 (-8280 2750);
PAINT MONO (-8280 2750);
FORCEPROP 2 LAST CDS_LIB standard
J 2
(-8000 2750);
DISPLAY INVISIBLE (-8000 2750);
FORCEPROP 1 LAST OFFPAGE TRUE
J 2
(-8325 2625);
DISPLAY 0.872340 (-8325 2625);
PAINT GREEN (-8325 2625);
DISPLAY INVISIBLE (-8325 2625);
FORCEPROP 1 LAST COMMENT_BODY TRUE
J 2
(-7950 2650);
DISPLAY 0.872340 (-7950 2650);
PAINT GREEN (-7950 2650);
DISPLAY INVISIBLE (-7950 2650);
FORCEPROP 2 LAST PATH I201
J 2
(-8475 2800);
DISPLAY 0.680851 (-8475 2800);
DISPLAY INVISIBLE (-8475 2800);
FORCEADD Q_RES..1
(-6900 2950);
FORCEPROP 1 LAST LOCATION R6310
J 0
(-7175 2950);
DISPLAY 0.808511 (-7175 2950);
FORCEPROP 0 LAST $SEC 1
J 0
(-7025 3050);
DISPLAY 0.680851 (-7025 3050);
PAINT MONO (-7025 3050);
DISPLAY INVISIBLE (-7025 3050);
FORCEPROP 0 LAST CDS_SEC 1
J 0
(-7025 3050);
DISPLAY 0.680851 (-7025 3050);
DISPLAY INVISIBLE (-7025 3050);
FORCEPROP 1 LASTPIN (-7000 2950) $PN 1
J 0
(-6988 2962);
DISPLAY 0.787234 (-6988 2962);
PAINT MONO (-6988 2962);
FORCEPROP 1 LASTPIN (-6800 2950) $PN 2
J 0
(-6838 2962);
DISPLAY 0.787234 (-6838 2962);
PAINT MONO (-6838 2962);
FORCEPROP 2 LAST ROOM USB3_HUB2_TI
J 0
(-7050 3025);
DISPLAY 0.553191 (-7050 3025);
PAINT RED (-7050 3025);
FORCEPROP 1 LAST VALUE 0
J 2
(-6750 2950);
DISPLAY 0.617021 (-6750 2950);
FORCEPROP 1 LAST MATERIAL CHIP
J 0
(-6800 2900);
DISPLAY 0.617021 (-6800 2900);
FORCEPROP 1 LAST TOLERANCE 5%
J 0
(-6725 2950);
DISPLAY 0.617021 (-6725 2950);
FORCEPROP 1 LAST PACK_TYPE 0402LF
J 0
(-7150 2900);
DISPLAY 0.617021 (-7150 2900);
FORCEPROP 2 LAST CDS_LIB pure_quanta
J 0
(-6900 2950);
DISPLAY INVISIBLE (-6900 2950);
FORCEPROP 1 LAST WATTAGE 1/16W
J 2
(-6700 2900);
DISPLAY 0.617021 (-6700 2900);
DISPLAY INVISIBLE (-6700 2900);
FORCEPROP 2 LAST BOM_COST VR_SYSTEM 
J 0
(-6950 3100);
DISPLAY 0.680851 (-6950 3100);
DISPLAY INVISIBLE (-6950 3100);
FORCEPROP 1 LAST PATH I202
J 0
(-6950 3100);
DISPLAY 0.978723 (-6950 3100);
PAINT WHITE (-6950 3100);
DISPLAY INVISIBLE (-6950 3100);
FORCEPROP 1 LAST PART_NUMBER CS00002JB13
J 0
(-7050 3000);
DISPLAY 0.617021 (-7050 3000);
DISPLAY INVISIBLE (-7050 3000);
FORCEADD UNIVERSAL_POWER..1
(-8450 3125);
FORCEPROP 3 LASTPIN (-8450 3075) SIG_NAME P3V3_AUX\g
J 0
(-8440 3085);
DISPLAY 0.659574 (-8440 3085);
PAINT MONO (-8440 3085);
DISPLAY INVISIBLE (-8440 3085);
FORCEPROP 1 LAST HDL_POWER P3V3_AUX
J 1
(-8450 3175);
DISPLAY 0.489362 (-8450 3175);
PAINT GREEN (-8450 3175);
FORCEPROP 2 LAST CDS_LIB pure_quanta_power
J 0
(-8450 3125);
DISPLAY INVISIBLE (-8450 3125);
FORCEPROP 2 LAST BOM_COST VR_SYSTEM
J 0
(-8450 3225);
DISPLAY 0.617021 (-8450 3225);
PAINT PURPLE (-8450 3225);
DISPLAY INVISIBLE (-8450 3225);
FORCEPROP 1 LAST PATH I204
J 0
(-8400 3150);
DISPLAY 0.872340 (-8400 3150);
PAINT AQUA (-8400 3150);
DISPLAY INVISIBLE (-8400 3150);
FORCEADD Q_RES..1
(-8125 2950);
FORCEPROP 1 LAST LOCATION R6312
J 0
(-8400 2975);
DISPLAY 0.808511 (-8400 2975);
FORCEPROP 2 LAST SEC 1
J 0
(-8175 3150);
DISPLAY 0.680851 (-8175 3150);
PAINT MONO (-8175 3150);
DISPLAY INVISIBLE (-8175 3150);
FORCEPROP 1 LASTPIN (-8225 2950) $PN 1
J 0
(-8213 2962);
DISPLAY 0.787234 (-8213 2962);
PAINT MONO (-8213 2962);
FORCEPROP 1 LASTPIN (-8025 2950) $PN 2
J 0
(-8063 2962);
DISPLAY 0.787234 (-8063 2962);
PAINT MONO (-8063 2962);
FORCEPROP 1 LAST MATERIAL CHIP
J 0
(-8350 2900);
DISPLAY 0.638298 (-8350 2900);
FORCEPROP 1 LAST VALUE 10K
J 2
(-7925 2950);
DISPLAY 0.638298 (-7925 2950);
FORCEPROP 1 LAST TOLERANCE 1%
J 0
(-7900 2950);
DISPLAY 0.638298 (-7900 2950);
FORCEPROP 2 LAST ROOM USB3_HUB2_TI
J 0
(-8225 3025);
DISPLAY 0.553191 (-8225 3025);
PAINT RED (-8225 3025);
FORCEPROP 1 LAST PACK_TYPE 0402LF
J 0
(-8000 2900);
DISPLAY 0.638298 (-8000 2900);
FORCEPROP 1 LAST WATTAGE 1/16W
J 2
(-8150 2800);
DISPLAY 0.638298 (-8150 2800);
DISPLAY INVISIBLE (-8150 2800);
FORCEPROP 2 LAST SEC_TYPE 0402LF
J 0
(-8175 3150);
DISPLAY 0.680851 (-8175 3150);
DISPLAY INVISIBLE (-8175 3150);
FORCEPROP 2 LAST CDS_LIB pure_quanta
J 0
(-8125 2950);
DISPLAY INVISIBLE (-8125 2950);
FORCEPROP 1 LAST PATH I205
J 0
(-8175 3100);
DISPLAY 0.978723 (-8175 3100);
PAINT WHITE (-8175 3100);
DISPLAY INVISIBLE (-8175 3100);
FORCEPROP 1 LAST PART_NUMBER CS31002FB08
J 0
(-8175 3050);
DISPLAY 0.978723 (-8175 3050);
DISPLAY INVISIBLE (-8175 3050);
FORCEADD OFFPAGE..3
(-3125 4250);
FORCEPROP 2 LAST $XR0 180 
J 0
(-2911 4250);
DISPLAY 0.638298 (-2911 4250);
PAINT MONO (-2911 4250);
FORCEPROP 2 LAST CDS_LIB standard
J 0
(-3125 4250);
DISPLAY INVISIBLE (-3125 4250);
FORCEPROP 1 LAST OFFPAGE TRUE
J 0
(-2800 4125);
DISPLAY 0.872340 (-2800 4125);
PAINT GREEN (-2800 4125);
DISPLAY INVISIBLE (-2800 4125);
FORCEPROP 1 LAST COMMENT_BODY TRUE
J 0
(-3175 4150);
DISPLAY 0.872340 (-3175 4150);
PAINT GREEN (-3175 4150);
DISPLAY INVISIBLE (-3175 4150);
FORCEPROP 2 LAST PATH I206
J 0
(-2900 4300);
DISPLAY 0.680851 (-2900 4300);
DISPLAY INVISIBLE (-2900 4300);
FORCEADD Q_RES..2
(-2900 1275);
FORCEPROP 1 LAST LOCATION R6331
J 0
(-2855 1400);
DISPLAY 0.787234 (-2855 1400);
FORCEPROP 0 LAST $SEC 1
J 0
(-2850 1500);
DISPLAY 0.680851 (-2850 1500);
PAINT MONO (-2850 1500);
DISPLAY INVISIBLE (-2850 1500);
FORCEPROP 0 LAST CDS_SEC 1
J 0
(-2850 1500);
DISPLAY 0.680851 (-2850 1500);
DISPLAY INVISIBLE (-2850 1500);
FORCEPROP 1 LASTPIN (-2900 1375) $PN 1
J 0
(-2895 1337);
DISPLAY 0.787234 (-2895 1337);
PAINT MONO (-2895 1337);
FORCEPROP 1 LASTPIN (-2900 1175) $PN 2
J 0
(-2895 1185);
DISPLAY 0.787234 (-2895 1185);
PAINT MONO (-2895 1185);
FORCEPROP 1 LAST TOLERANCE 1%
J 0
(-2855 1300);
DISPLAY 0.787234 (-2855 1300);
FORCEPROP 1 LAST VALUE 9.53K
J 0
(-2855 1350);
DISPLAY 0.787234 (-2855 1350);
FORCEPROP 1 LAST MATERIAL CHIP
J 0
(-2860 1200);
DISPLAY 0.787234 (-2860 1200);
FORCEPROP 1 LAST WATTAGE 1/16W
J 0
(-2860 1250);
DISPLAY 0.787234 (-2860 1250);
FORCEPROP 1 LAST PACK_TYPE 0402LF
J 0
(-2860 1100);
DISPLAY 0.787234 (-2860 1100);
FORCEPROP 2 LAST ROOM USB3_HUB2_TI
J 0
(-2850 1450);
DISPLAY 0.680851 (-2850 1450);
PAINT RED (-2850 1450);
FORCEPROP 2 LAST CDS_LIB pure_quanta
J 0
(-2900 1275);
DISPLAY INVISIBLE (-2900 1275);
FORCEPROP 1 LAST PATH I207
J 0
(-2850 1450);
DISPLAY 0.978723 (-2850 1450);
PAINT WHITE (-2850 1450);
DISPLAY INVISIBLE (-2850 1450);
FORCEPROP 1 LAST PART_NUMBER CS29532FB06
J 0
(-2860 1150);
DISPLAY 0.787234 (-2860 1150);
DISPLAY INVISIBLE (-2860 1150);
FORCEADD Q_RES..2
R 2
(-3000 1275);
FORCEPROP 1 LAST LOCATION R6332
J 2
(-3045 1400);
DISPLAY 0.787234 (-3045 1400);
FORCEPROP 0 LAST $SEC 1
J 0
(-3250 1500);
DISPLAY 0.680851 (-3250 1500);
PAINT MONO (-3250 1500);
DISPLAY INVISIBLE (-3250 1500);
FORCEPROP 0 LAST CDS_SEC 1
J 0
(-3250 1500);
DISPLAY 0.680851 (-3250 1500);
DISPLAY INVISIBLE (-3250 1500);
FORCEPROP 1 LASTPIN (-3000 1375) $PN 1
J 2
(-3005 1337);
DISPLAY 0.787234 (-3005 1337);
PAINT MONO (-3005 1337);
FORCEPROP 1 LASTPIN (-3000 1175) $PN 2
J 2
(-3005 1185);
DISPLAY 0.787234 (-3005 1185);
PAINT MONO (-3005 1185);
FORCEPROP 1 LAST MATERIAL CHIP
J 2
(-3040 1200);
DISPLAY 0.787234 (-3040 1200);
FORCEPROP 1 LAST PACK_TYPE 0402LF
J 2
(-3040 1100);
DISPLAY 0.787234 (-3040 1100);
FORCEPROP 1 LAST TOLERANCE 1%
J 2
(-3045 1300);
DISPLAY 0.787234 (-3045 1300);
FORCEPROP 1 LAST VALUE 12K
J 2
(-3045 1350);
DISPLAY 0.787234 (-3045 1350);
FORCEPROP 1 LAST WATTAGE 1/16W
J 2
(-3040 1250);
DISPLAY 0.787234 (-3040 1250);
FORCEPROP 2 LAST ROOM USB3_HUB2_MRP
J 0
(-3475 1450);
DISPLAY 0.680851 (-3475 1450);
PAINT RED (-3475 1450);
FORCEPROP 2 LAST CDS_LIB pure_quanta
J 2
(-3000 1275);
DISPLAY INVISIBLE (-3000 1275);
FORCEPROP 1 LAST PATH I208
J 2
(-3050 1450);
DISPLAY 0.978723 (-3050 1450);
PAINT WHITE (-3050 1450);
DISPLAY INVISIBLE (-3050 1450);
FORCEPROP 1 LAST PART_NUMBER CS31202FB04
J 2
(-3040 1150);
DISPLAY 0.787234 (-3040 1150);
DISPLAY INVISIBLE (-3040 1150);
FORCEADD GND..1
(-2900 1000);
FORCEPROP 3 LASTPIN (-2900 1050) SIG_NAME GND\g
J 0
(-2890 1060);
DISPLAY 0.659574 (-2890 1060);
PAINT MONO (-2890 1060);
DISPLAY INVISIBLE (-2890 1060);
FORCEPROP 2 LAST CDS_LIB pure_quanta_power
J 0
(-2900 1000);
DISPLAY INVISIBLE (-2900 1000);
FORCEPROP 1 LAST SIZE 1B
J 0
(-2825 950);
DISPLAY 1.170213 (-2825 950);
PAINT AQUA (-2825 950);
DISPLAY INVISIBLE (-2825 950);
FORCEPROP 1 LAST HDL_POWER GND
J 0
(-2900 1150);
DISPLAY 1.170213 (-2900 1150);
PAINT GREEN (-2900 1150);
DISPLAY INVISIBLE (-2900 1150);
FORCEPROP 1 LAST PATH I209
J 0
(-2825 1000);
DISPLAY 0.872340 (-2825 1000);
PAINT AQUA (-2825 1000);
DISPLAY INVISIBLE (-2825 1000);
FORCEADD GND..1
(-3000 1000);
FORCEPROP 3 LASTPIN (-3000 1050) SIG_NAME GND\g
J 0
(-2990 1060);
DISPLAY 0.659574 (-2990 1060);
PAINT MONO (-2990 1060);
DISPLAY INVISIBLE (-2990 1060);
FORCEPROP 2 LAST CDS_LIB pure_quanta_power
J 0
(-3000 1000);
DISPLAY INVISIBLE (-3000 1000);
FORCEPROP 1 LAST SIZE 1B
J 0
(-2925 950);
DISPLAY 1.170213 (-2925 950);
PAINT AQUA (-2925 950);
DISPLAY INVISIBLE (-2925 950);
FORCEPROP 1 LAST HDL_POWER GND
J 0
(-3000 1150);
DISPLAY 1.170213 (-3000 1150);
PAINT GREEN (-3000 1150);
DISPLAY INVISIBLE (-3000 1150);
FORCEPROP 1 LAST PATH I210
J 0
(-2925 1000);
DISPLAY 0.872340 (-2925 1000);
PAINT AQUA (-2925 1000);
DISPLAY INVISIBLE (-2925 1000);
FORCEADD GND..1
(-3675 950);
FORCEPROP 3 LASTPIN (-3675 1000) SIG_NAME GND\g
J 0
(-3665 1010);
DISPLAY 0.659574 (-3665 1010);
PAINT MONO (-3665 1010);
DISPLAY INVISIBLE (-3665 1010);
FORCEPROP 1 LAST SIZE 1B
J 0
(-3600 900);
DISPLAY 1.170213 (-3600 900);
PAINT AQUA (-3600 900);
DISPLAY INVISIBLE (-3600 900);
FORCEPROP 2 LAST CDS_LIB pure_quanta_power
J 0
(-3675 950);
DISPLAY INVISIBLE (-3675 950);
FORCEPROP 1 LAST HDL_POWER GND
J 0
(-3675 1100);
DISPLAY 1.170213 (-3675 1100);
PAINT GREEN (-3675 1100);
DISPLAY INVISIBLE (-3675 1100);
FORCEPROP 1 LAST PATH I211
J 0
(-3600 950);
DISPLAY 0.872340 (-3600 950);
PAINT AQUA (-3600 950);
DISPLAY INVISIBLE (-3600 950);
FORCEADD Q_RES..2
(-8025 6300);
FORCEPROP 1 LAST LOCATION R6320
J 0
(-7980 6425);
DISPLAY 0.638298 (-7980 6425);
FORCEPROP 0 LAST $SEC 1
J 0
(-7975 6525);
DISPLAY 0.680851 (-7975 6525);
PAINT MONO (-7975 6525);
DISPLAY INVISIBLE (-7975 6525);
FORCEPROP 0 LAST CDS_SEC 1
J 0
(-7975 6525);
DISPLAY 0.680851 (-7975 6525);
DISPLAY INVISIBLE (-7975 6525);
FORCEPROP 1 LASTPIN (-8025 6400) $PN 1
J 0
(-8020 6362);
DISPLAY 0.787234 (-8020 6362);
PAINT MONO (-8020 6362);
FORCEPROP 1 LASTPIN (-8025 6200) $PN 2
J 0
(-8020 6210);
DISPLAY 0.787234 (-8020 6210);
PAINT MONO (-8020 6210);
FORCEPROP 2 LAST ROOM USB3_HUB2_MRP
J 0
(-7975 6475);
DISPLAY 0.553191 (-7975 6475);
PAINT RED (-7975 6475);
FORCEPROP 1 LAST MATERIAL EMPTY
J 0
(-7985 6225);
DISPLAY 0.638298 (-7985 6225);
PAINT RED (-7985 6225);
FORCEPROP 1 LAST WATTAGE 1/16W
J 0
(-7985 6275);
DISPLAY 0.638298 (-7985 6275);
FORCEPROP 1 LAST TOLERANCE 1%
J 0
(-7980 6325);
DISPLAY 0.638298 (-7980 6325);
FORCEPROP 1 LAST VALUE 10K
J 0
(-7980 6375);
DISPLAY 0.638298 (-7980 6375);
FORCEPROP 1 LAST PACK_TYPE 0402LF
J 0
(-7985 6125);
DISPLAY 0.638298 (-7985 6125);
FORCEPROP 2 LAST CDS_LIB pure_quanta
J 0
(-8025 6300);
DISPLAY INVISIBLE (-8025 6300);
FORCEPROP 1 LAST PATH I212
J 0
(-7975 6475);
DISPLAY 0.978723 (-7975 6475);
PAINT WHITE (-7975 6475);
DISPLAY INVISIBLE (-7975 6475);
FORCEPROP 1 LAST PART_NUMBER CS31002FB08
J 0
(-7985 6175);
DISPLAY 0.638298 (-7985 6175);
DISPLAY INVISIBLE (-7985 6175);
FORCEADD Q_RES..2
(-8175 3825);
FORCEPROP 1 LAST LOCATION R6329
J 0
(-8130 3950);
DISPLAY 0.510638 (-8130 3950);
FORCEPROP 0 LAST $SEC 1
J 0
(-8125 4050);
DISPLAY 0.680851 (-8125 4050);
PAINT MONO (-8125 4050);
DISPLAY INVISIBLE (-8125 4050);
FORCEPROP 0 LAST CDS_SEC 1
J 0
(-8125 4050);
DISPLAY 0.680851 (-8125 4050);
DISPLAY INVISIBLE (-8125 4050);
FORCEPROP 1 LASTPIN (-8175 3925) $PN 1
J 0
(-8170 3887);
DISPLAY 0.787234 (-8170 3887);
PAINT MONO (-8170 3887);
FORCEPROP 1 LASTPIN (-8175 3725) $PN 2
J 0
(-8170 3735);
DISPLAY 0.787234 (-8170 3735);
PAINT MONO (-8170 3735);
FORCEPROP 1 LAST PACK_TYPE 0402LF
J 0
(-8125 3700);
DISPLAY 0.510638 (-8125 3700);
FORCEPROP 1 LAST MATERIAL EMPTY
J 0
(-8135 3750);
DISPLAY 0.510638 (-8135 3750);
PAINT RED (-8135 3750);
FORCEPROP 1 LAST TOLERANCE 1%
J 0
(-8130 3850);
DISPLAY 0.510638 (-8130 3850);
FORCEPROP 2 LAST ROOM USB3_HUB2_TI
J 0
(-8450 3875);
DISPLAY 0.446809 (-8450 3875);
PAINT RED (-8450 3875);
FORCEPROP 1 LAST WATTAGE 1/16W
J 0
(-8135 3800);
DISPLAY 0.510638 (-8135 3800);
FORCEPROP 1 LAST VALUE 10K
J 0
(-8130 3900);
DISPLAY 0.510638 (-8130 3900);
FORCEPROP 2 LAST CDS_LIB pure_quanta
J 0
(-8175 3825);
DISPLAY INVISIBLE (-8175 3825);
FORCEPROP 1 LAST PATH I213
J 0
(-8125 4000);
DISPLAY 0.978723 (-8125 4000);
PAINT WHITE (-8125 4000);
DISPLAY INVISIBLE (-8125 4000);
FORCEPROP 1 LAST PART_NUMBER CS31002FB08
J 0
(-8135 3700);
DISPLAY 0.510638 (-8135 3700);
DISPLAY INVISIBLE (-8135 3700);
FORCEADD Q_RES..2
(-8500 1100);
FORCEPROP 1 LAST LOCATION R6326
J 0
(-8455 1225);
DISPLAY 0.638298 (-8455 1225);
FORCEPROP 0 LAST $SEC 1
J 0
(-8450 1275);
DISPLAY 0.680851 (-8450 1275);
PAINT MONO (-8450 1275);
DISPLAY INVISIBLE (-8450 1275);
FORCEPROP 0 LAST CDS_SEC 1
J 0
(-8450 1275);
DISPLAY 0.680851 (-8450 1275);
DISPLAY INVISIBLE (-8450 1275);
FORCEPROP 1 LASTPIN (-8500 1200) $PN 1
J 0
(-8495 1162);
DISPLAY 0.787234 (-8495 1162);
PAINT MONO (-8495 1162);
FORCEPROP 1 LASTPIN (-8500 1000) $PN 2
J 0
(-8495 1010);
DISPLAY 0.787234 (-8495 1010);
PAINT MONO (-8495 1010);
FORCEPROP 2 LAST ROOM USB3_HUB2_MRP
J 0
(-8475 975);
DISPLAY 0.553191 (-8475 975);
PAINT RED (-8475 975);
FORCEPROP 1 LAST VALUE 4.7K
J 0
(-8455 1175);
DISPLAY 0.510638 (-8455 1175);
FORCEPROP 1 LAST TOLERANCE 1%
J 0
(-8450 1150);
DISPLAY 0.510638 (-8450 1150);
FORCEPROP 1 LAST MATERIAL CHIP
J 0
(-8450 1075);
DISPLAY 0.510638 (-8450 1075);
FORCEPROP 1 LAST WATTAGE 1/16W
J 0
(-8450 1125);
DISPLAY 0.510638 (-8450 1125);
FORCEPROP 1 LAST PACK_TYPE 0402LF
J 0
(-8450 1025);
DISPLAY 0.510638 (-8450 1025);
FORCEPROP 2 LAST CDS_LIB pure_quanta
J 0
(-8500 1100);
DISPLAY INVISIBLE (-8500 1100);
FORCEPROP 1 LAST PATH I89
J 0
(-8450 1275);
DISPLAY 0.978723 (-8450 1275);
PAINT WHITE (-8450 1275);
DISPLAY INVISIBLE (-8450 1275);
FORCEPROP 1 LAST PART_NUMBER CS24702FB06
J 0
(-8450 1025);
DISPLAY 0.404255 (-8450 1025);
DISPLAY INVISIBLE (-8450 1025);
FORCEADD GND..1
(-8500 875);
FORCEPROP 3 LASTPIN (-8500 925) SIG_NAME GND\g
J 0
(-8490 935);
DISPLAY 0.659574 (-8490 935);
PAINT MONO (-8490 935);
DISPLAY INVISIBLE (-8490 935);
FORCEPROP 2 LAST CDS_LIB pure_quanta_power
J 0
(-8500 875);
DISPLAY INVISIBLE (-8500 875);
FORCEPROP 1 LAST SIZE 1B
J 0
(-8425 825);
DISPLAY 1.170213 (-8425 825);
PAINT AQUA (-8425 825);
DISPLAY INVISIBLE (-8425 825);
FORCEPROP 1 LAST HDL_POWER GND
J 0
(-8500 1025);
DISPLAY 1.170213 (-8500 1025);
PAINT GREEN (-8500 1025);
DISPLAY INVISIBLE (-8500 1025);
FORCEPROP 1 LAST PATH I90
J 0
(-8425 875);
DISPLAY 0.872340 (-8425 875);
PAINT AQUA (-8425 875);
DISPLAY INVISIBLE (-8425 875);
FORCEADD Q_RES..2
(-8500 1475);
FORCEPROP 1 LAST LOCATION R6327
J 0
(-8455 1600);
DISPLAY 0.638298 (-8455 1600);
FORCEPROP 0 LAST $SEC 1
J 0
(-8450 1700);
DISPLAY 0.680851 (-8450 1700);
PAINT MONO (-8450 1700);
DISPLAY INVISIBLE (-8450 1700);
FORCEPROP 0 LAST CDS_SEC 1
J 0
(-8450 1700);
DISPLAY 0.680851 (-8450 1700);
DISPLAY INVISIBLE (-8450 1700);
FORCEPROP 1 LASTPIN (-8500 1575) $PN 1
J 0
(-8495 1537);
DISPLAY 0.787234 (-8495 1537);
PAINT MONO (-8495 1537);
FORCEPROP 1 LASTPIN (-8500 1375) $PN 2
J 0
(-8495 1385);
DISPLAY 0.787234 (-8495 1385);
PAINT MONO (-8495 1385);
FORCEPROP 2 LAST ROOM USB3_HUB2_MRP
J 0
(-8450 1650);
DISPLAY 0.553191 (-8450 1650);
PAINT RED (-8450 1650);
FORCEPROP 1 LAST WATTAGE 1/16W
J 0
(-8460 1450);
DISPLAY 0.510638 (-8460 1450);
FORCEPROP 1 LAST VALUE 4.7K
J 0
(-8455 1550);
DISPLAY 0.510638 (-8455 1550);
FORCEPROP 1 LAST TOLERANCE 1%
J 0
(-8455 1500);
DISPLAY 0.510638 (-8455 1500);
FORCEPROP 1 LAST PACK_TYPE 0402LF
J 0
(-8450 1350);
DISPLAY 0.510638 (-8450 1350);
FORCEPROP 1 LAST MATERIAL EMPTY
J 0
(-8460 1400);
DISPLAY 0.510638 (-8460 1400);
FORCEPROP 2 LAST CDS_LIB pure_quanta
J 0
(-8500 1475);
DISPLAY INVISIBLE (-8500 1475);
FORCEPROP 1 LAST PATH I91
J 0
(-8450 1650);
DISPLAY 0.978723 (-8450 1650);
PAINT WHITE (-8450 1650);
DISPLAY INVISIBLE (-8450 1650);
FORCEPROP 1 LAST PART_NUMBER CS24702FB06
J 0
(-8460 1350);
DISPLAY 0.638298 (-8460 1350);
DISPLAY INVISIBLE (-8460 1350);
FORCEADD UNIVERSAL_POWER..1
(-8500 1925);
FORCEPROP 3 LASTPIN (-8500 1875) SIG_NAME P3V3_AUX\g
J 0
(-8490 1885);
DISPLAY 0.659574 (-8490 1885);
PAINT MONO (-8490 1885);
DISPLAY INVISIBLE (-8490 1885);
FORCEPROP 1 LAST HDL_POWER P3V3_AUX
J 1
(-8500 1975);
DISPLAY 0.489362 (-8500 1975);
PAINT GREEN (-8500 1975);
FORCEPROP 2 LAST CDS_LIB pure_quanta_power
J 0
(-8500 1925);
DISPLAY INVISIBLE (-8500 1925);
FORCEPROP 2 LAST BOM_COST VR_SYSTEM
J 0
(-8500 2025);
DISPLAY 0.617021 (-8500 2025);
PAINT PURPLE (-8500 2025);
DISPLAY INVISIBLE (-8500 2025);
FORCEPROP 1 LAST PATH I92
J 0
(-8450 1950);
DISPLAY 0.872340 (-8450 1950);
PAINT AQUA (-8450 1950);
DISPLAY INVISIBLE (-8450 1950);
FORCEADD DNS..1
(-7925 6300);
PAINT RED (-7925 6300);
FORCEPROP 2 LAST CDS_LIB mstr_misc
J 0
(-7925 6300);
DISPLAY INVISIBLE (-7925 6300);
FORCEPROP 2 LAST BOM_COST VR_SYSTEM 
J 0
(-8100 6475);
DISPLAY 0.680851 (-8100 6475);
DISPLAY INVISIBLE (-8100 6475);
FORCEPROP 1 LAST COMMENT_BODY TRUE
J 0
(-7925 6300);
DISPLAY INVISIBLE (-7925 6300);
FORCEADD DNS..1
(-7075 4325);
PAINT RED (-7075 4325);
FORCEPROP 2 LAST CDS_LIB mstr_misc
J 0
(-7075 4325);
DISPLAY INVISIBLE (-7075 4325);
FORCEPROP 2 LAST BOM_COST VR_SYSTEM 
J 0
(-7250 4500);
DISPLAY 0.680851 (-7250 4500);
DISPLAY INVISIBLE (-7250 4500);
FORCEPROP 1 LAST COMMENT_BODY TRUE
J 0
(-7075 4325);
DISPLAY INVISIBLE (-7075 4325);
FORCEADD DNS..1
(-975 5600);
PAINT RED (-975 5600);
FORCEPROP 2 LAST CDS_LIB mstr_misc
J 0
(-975 5600);
DISPLAY INVISIBLE (-975 5600);
FORCEPROP 2 LAST BOM_COST VR_SYSTEM 
J 0
(-1150 5775);
DISPLAY 0.680851 (-1150 5775);
DISPLAY INVISIBLE (-1150 5775);
FORCEPROP 1 LAST COMMENT_BODY TRUE
J 0
(-975 5600);
DISPLAY INVISIBLE (-975 5600);
FORCEADD DNS..1
(-8400 1500);
PAINT RED (-8400 1500);
FORCEPROP 2 LAST CDS_LIB mstr_misc
J 0
(-8400 1500);
DISPLAY INVISIBLE (-8400 1500);
FORCEPROP 2 LAST BOM_COST VR_SYSTEM 
J 0
(-8575 1675);
DISPLAY 0.680851 (-8575 1675);
DISPLAY INVISIBLE (-8575 1675);
FORCEPROP 1 LAST COMMENT_BODY TRUE
J 0
(-8400 1500);
DISPLAY INVISIBLE (-8400 1500);
FORCEADD DNS..1
(-7625 3425);
PAINT RED (-7625 3425);
FORCEPROP 2 LAST CDS_LIB mstr_misc
J 0
(-7625 3425);
DISPLAY INVISIBLE (-7625 3425);
FORCEPROP 2 LAST BOM_COST VR_SYSTEM 
J 0
(-7800 3600);
DISPLAY 0.680851 (-7800 3600);
DISPLAY INVISIBLE (-7800 3600);
FORCEPROP 1 LAST COMMENT_BODY TRUE
J 0
(-7625 3425);
DISPLAY INVISIBLE (-7625 3425);
FORCEADD DNS..1
(-8350 5825);
PAINT RED (-8350 5825);
FORCEPROP 2 LAST BOM_COST VR_SYSTEM 
J 0
(-8525 6000);
DISPLAY 0.680851 (-8525 6000);
DISPLAY INVISIBLE (-8525 6000);
FORCEPROP 2 LAST CDS_LIB mstr_misc
J 0
(-8350 5825);
DISPLAY INVISIBLE (-8350 5825);
FORCEPROP 1 LAST COMMENT_BODY TRUE
J 0
(-8350 5825);
DISPLAY INVISIBLE (-8350 5825);
FORCEADD QUANTA_TITLE_BLOCK_C..1
(-100 100);
FORCEPROP 0 LAST CDS_CON_LAST_MODIFIED Thu Sep 14 16:12:48 2023
J 0
(-1985 115);
DISPLAY INVISIBLE (-1985 115);
FORCEPROP 1 LAST CUSTOM_TXT_CDS <CON_LAST_MODIFIED>
J 0
(-1985 115);
DISPLAY 0.978723 (-1985 115);
FORCEPROP 2 LAST CUSTOM_TXT_CDS <XR_PAGE_TITLE>
J 0
(-7990 5350);
DISPLAY 0.638298 (-7990 5350);
PAINT PINK (-7990 5350);
DISPLAY INVISIBLE (-7990 5350);
FORCEPROP 1 LAST CUSTOM_TXT_CDS <NAME_2>
J 0
(-3275 150);
FORCEPROP 1 LAST CUSTOM_TXT_CDS <NAME_1>
J 0
(-3275 275);
FORCEPROP 1 LAST CUSTOM_TXT_CDS <Q_NUMBER>
J 0
(-1503 203);
DISPLAY 1.212766 (-1503 203);
FORCEPROP 1 LAST CUSTOM_TXT_CDS <Q_PROJ>
J 0
(-2482 202);
DISPLAY 1.212766 (-2482 202);
FORCEPROP 1 LAST CUSTOM_TXT_CDS <Q_REV>
J 0
(-284 203);
DISPLAY 1.212766 (-284 203);
FORCEPROP 1 LAST CUSTOM_TXT_CDS <CON_PAGE_NUM> OF <CON_TOTAL_PAGES>
J 0
(-546 118);
DISPLAY 0.978723 (-546 118);
FORCEPROP 1 LAST Q_TITLE USB3.0 EXT HUB 2ND(1/2)
J 0
(-9466 126);
DISPLAY 2.446809 (-9466 126);
PAINT GREEN (-9466 126);
FORCEPROP 2 LAST CDS_LIB pure_quanta
J 0
(-100 100);
DISPLAY INVISIBLE (-100 100);
FORCEPROP 1 LAST CDS_LMAN_SYM_OUTLINE -9475,6775,100,-125
J 0
(-100 100);
DISPLAY 0.468085 (-100 100);
PAINT GREEN (-100 100);
DISPLAY INVISIBLE (-100 100);
FORCEPROP 2 LAST PAGE_BORDER TRUE
J 0
(-7990 5350);
DISPLAY 0.638298 (-7990 5350);
PAINT PINK (-7990 5350);
DISPLAY INVISIBLE (-7990 5350);
FORCEPROP 2 LAST CDS_XR_PAGE_TITLE CR-178 : @T6G_MB_LIB.T6G(SCH_1):PAGE178
J 0
(-7990 5350);
DISPLAY 0.638298 (-7990 5350);
PAINT PINK (-7990 5350);
DISPLAY INVISIBLE (-7990 5350);
FORCEPROP 1 LAST Q_DEPT BU9
J 1
(-3863 149);
DISPLAY 1.957447 (-3863 149);
PAINT GREEN (-3863 149);
DISPLAY INVISIBLE (-3863 149);
FORCEPROP 1 LAST COMMENT_BODY TRUE
J 0
(-88 87);
DISPLAY 0.978723 (-88 87);
PAINT GREEN (-88 87);
DISPLAY INVISIBLE (-88 87);
FORCEADD DNS..1
(-8075 3800);
PAINT RED (-8075 3800);
FORCEPROP 2 LAST BOM_COST VR_SYSTEM 
J 0
(-8250 3975);
DISPLAY 0.680851 (-8250 3975);
DISPLAY INVISIBLE (-8250 3975);
FORCEPROP 2 LAST CDS_LIB mstr_misc
J 0
(-8075 3800);
DISPLAY INVISIBLE (-8075 3800);
FORCEPROP 1 LAST COMMENT_BODY TRUE
J 0
(-8075 3800);
DISPLAY INVISIBLE (-8075 3800);
FORCEADD DNS..1
(-8675 4950);
PAINT RED (-8675 4950);
FORCEPROP 2 LAST CDS_LIB mstr_misc
J 0
(-8675 4950);
DISPLAY INVISIBLE (-8675 4950);
FORCEPROP 2 LAST BOM_COST VR_SYSTEM 
J 0
(-8850 5125);
DISPLAY 0.680851 (-8850 5125);
DISPLAY INVISIBLE (-8850 5125);
FORCEPROP 1 LAST COMMENT_BODY TRUE
J 0
(-8675 4950);
DISPLAY INVISIBLE (-8675 4950);
WIRE 16 -1 (-1000 5750)(-1000 5850);
WIRE 16 -1 (-1000 5000)(-1000 4925);
WIRE 16 -1 (-8175 3975)(-8175 3925);
WIRE 16 -1 (-8175 3325)(-8175 3225);
WIRE 16 -1 (-7575 3350)(-7575 3325);
WIRE 16 -1 (-7925 675)(-7925 425);
WIRE 16 -1 (-9100 5300)(-9100 5225);
WIRE 16 -1 (-9100 5975)(-9100 5850);
WIRE 16 -1 (-8025 6400)(-8025 6500);
WIRE 16 -1 (-8025 5775)(-8025 5700);
WIRE 16 -1 (-8350 5800)(-8350 5700);
WIRE 16 -1 (-2400 5150)(-1775 5150);
WIRE 16 -1 (-1775 5150)(-1775 5200);
WIRE 16 -1 (-2350 3000)(-1300 3000);
WIRE 16 -1 (-1300 3000)(-1300 3050);
WIRE 16 -1 (-8750 3050)(-8750 3300);
WIRE 16 -1 (-2200 2050)(-1650 2050);
WIRE 16 -1 (-1650 2050)(-1650 2100);
WIRE 16 -1 (-2350 3200)(-1300 3200);
WIRE 16 -1 (-2350 3250)(-1675 3250);
WIRE 16 -1 (-1675 3250)(-1675 3275);
WIRE 16 -1 (-7175 4275)(-7400 4275);
WIRE 16 -1 (-7400 4275)(-7400 4375);
WIRE 16 -1 (-9075 2225)(-9075 2300);
WIRE 16 -1 (-9075 1550)(-9075 1525);
WIRE 16 -1 (-9200 3175)(-9200 3250);
WIRE 16 -1 (-7575 2025)(-7575 2125);
WIRE 16 -1 (-8025 2025)(-8025 2125);
WIRE 16 -1 (-6300 800)(-6500 800);
WIRE 16 -1 (-6500 800)(-6500 600);
WIRE 16 -1 (-9175 4950)(-9175 5000);
WIRE 16 -1 (-8675 5350)(-8675 5400);
WIRE 16 -1 (-8675 4875)(-8675 4825);
WIRE 16 -1 (-2900 1175)(-2900 1050);
WIRE 16 -1 (-3000 1175)(-3000 1050);
WIRE 16 -1 (-4075 1300)(-3675 1300);
WIRE 16 -1 (-3675 1300)(-3675 1000);
WIRE 16 -1 (-8500 1000)(-8500 925);
WIRE 16 -1 (-8500 1575)(-8500 1875);
WIRE 16 -1 (-6675 6025)(-6875 6025);
WIRE 16 -1 (-6675 5550)(-6675 6025);
WIRE 16 -1 (-6675 5550)(-5625 5550);
FORCEPROP 2 LAST SIG_NAME USB_HUB2_TI_USB_VBUS_MRP_RESET_N
J 0
(-6635 5575);
DISPLAY 0.553191 (-6635 5575);
FORCEPROP 2 LASTPROP $XRERR UNIQUE?
J 0
(-6875 5575);
DISPLAY 0.638298 (-6875 5575);
PAINT MONO (-6875 5575);
DISPLAY INVISIBLE (-6875 5575);
WIRE 16 -1 (-6875 5550)(-6675 5550);
FORCEPROP 0 LAST $PNN USB_HUB2_TI_USB_VBUS_MRP_RESET_
J 0
(-6735 5586);
DISPLAY INVISIBLE (-6735 5586);
WIRE 16 -1 (-4075 2050)(-2400 2050);
FORCEPROP 2 LAST SIG_NAME USB_HUB2_TI_USB_SSRXM_DN4_MRP_VDD12
J 0
(-3885 2060);
DISPLAY 0.680851 (-3885 2060);
FORCEPROP 2 LASTPROP $XRERR UNIQUE?
J 0
(-4125 2060);
DISPLAY 0.638298 (-4125 2060);
PAINT MONO (-4125 2060);
DISPLAY INVISIBLE (-4125 2060);
WIRE 16 -1 (-4075 1500)(-3000 1500);
FORCEPROP 2 LAST SIG_NAME USB_HUB2_TI_USB_R1_MRP_RBIAS
J 0
(-3960 1510);
DISPLAY 0.553191 (-3960 1510);
FORCEPROP 2 LASTPROP $XRERR UNIQUE?
J 0
(-4200 1510);
DISPLAY 0.638298 (-4200 1510);
PAINT MONO (-4200 1510);
DISPLAY INVISIBLE (-4200 1510);
WIRE 16 -1 (-3000 1500)(-2900 1500);
WIRE 16 -1 (-3000 1375)(-3000 1500);
WIRE 16 -1 (-2900 1500)(-2900 1375);
WIRE 16 -1 (-8450 3075)(-8450 2950);
WIRE 16 -1 (-8450 2950)(-8225 2950);
WIRE 16 -1 (-7575 4425)(-7575 4050);
WIRE 16 -1 (-7575 4050)(-7150 4050);
WIRE 16 -1 (-7925 3900)(-7300 3900);
WIRE 16 -1 (-7925 4075)(-7925 3900);
WIRE 16 -1 (-4075 3000)(-2550 3000);
FORCEPROP 2 LAST SIG_NAME USB_HUB2_TI_USB_SSRXM_DN3_MRP_VDD12
J 0
(-3960 3010);
DISPLAY 0.680851 (-3960 3010);
FORCEPROP 2 LASTPROP $XRERR UNIQUE?
J 0
(-4200 3010);
DISPLAY 0.638298 (-4200 3010);
PAINT MONO (-4200 3010);
DISPLAY INVISIBLE (-4200 3010);
WIRE 16 -1 (-4075 3200)(-2550 3200);
FORCEPROP 0 LAST SIG_NAME USB_HUB2_TI_USB_DM_DN3_MRP_VDD33
J 0
(-3910 3200);
DISPLAY 0.680851 (-3910 3200);
FORCEPROP 2 LASTPROP $XRERR UNIQUE?
J 0
(-4150 3200);
DISPLAY 0.638298 (-4150 3200);
PAINT MONO (-4150 3200);
DISPLAY INVISIBLE (-4150 3200);
WIRE 16 -1 (-2550 3250)(-4075 3250);
FORCEPROP 2 LAST SIG_NAME USB_HUB2_TI_USB_DP_DN3_MRP_VDD12
J 0
(-3910 3275);
DISPLAY 0.680851 (-3910 3275);
FORCEPROP 2 LASTPROP $XRERR UNIQUE?
J 0
(-4150 3275);
DISPLAY 0.638298 (-4150 3275);
PAINT MONO (-4150 3275);
DISPLAY INVISIBLE (-4150 3275);
WIRE 16 -1 (-4075 4050)(-3100 4050);
FORCEPROP 2 LAST SIG_NAME USB3_CPU0_BMC_RX_C2_DN
J 0
(-3910 4060);
DISPLAY 0.680851 (-3910 4060);
WIRE 16 -1 (-4075 4100)(-3100 4100);
FORCEPROP 2 LAST SIG_NAME USB3_CPU0_BMC_RX_C2_DP
J 0
(-3910 4110);
DISPLAY 0.680851 (-3910 4110);
WIRE 16 -1 (-4075 4250)(-3175 4250);
FORCEPROP 2 LAST SIG_NAME USB2_CPU0_P0_HUB2_R_DN
J 0
(-3960 4260);
DISPLAY 0.680851 (-3960 4260);
WIRE 16 -1 (-4075 4300)(-3175 4300);
FORCEPROP 2 LAST SIG_NAME USB2_CPU0_P0_HUB2_R_DP
J 0
(-3960 4310);
DISPLAY 0.680851 (-3960 4310);
WIRE 16 -1 (-2275 5350)(-1000 5350);
FORCEPROP 2 LAST SIG_NAME USB_HUB2_MRP_CFG_STRAP
J 0
(-1760 5360);
DISPLAY 0.680851 (-1760 5360);
FORCEPROP 2 LASTPROP $XRERR UNIQUE?
J 0
(-2000 5360);
DISPLAY 0.638298 (-2000 5360);
PAINT MONO (-2000 5360);
DISPLAY INVISIBLE (-2000 5360);
WIRE 16 -1 (-1000 5550)(-1000 5350);
WIRE 16 -1 (-1000 5350)(-1000 5200);
WIRE 16 -1 (-4075 5150)(-2600 5150);
FORCEPROP 2 LAST SIG_NAME USB_HUB2_TI_USB_SSRXP_DN1_MRP_VDD12
J 0
(-3960 5160);
DISPLAY 0.680851 (-3960 5160);
FORCEPROP 2 LASTPROP $XRERR UNIQUE?
J 0
(-4200 5160);
DISPLAY 0.638298 (-4200 5160);
PAINT MONO (-4200 5160);
DISPLAY INVISIBLE (-4200 5160);
WIRE 16 -1 (-4075 5350)(-2475 5350);
FORCEPROP 2 LAST SIG_NAME USB_HUB2_TI_USB_DP_DN1_MRP_CFG_STRAP
J 0
(-3935 5375);
DISPLAY 0.680851 (-3935 5375);
FORCEPROP 2 LASTPROP $XRERR UNIQUE?
J 0
(-4175 5375);
DISPLAY 0.638298 (-4175 5375);
PAINT MONO (-4175 5375);
DISPLAY INVISIBLE (-4175 5375);
WIRE 16 -1 (-5625 1450)(-5625 1500);
WIRE 16 -1 (-5625 1450)(-6875 1450);
FORCEPROP 2 LAST SIG_NAME USB_HUB2_TI_NC_MRP_ATEST
J 0
(-6560 1460);
DISPLAY 0.680851 (-6560 1460);
WIRE 16 -1 (-5625 1300)(-6575 1300);
FORCEPROP 2 LAST SIG_NAME USB_HUB2_TI_TEST_MRP_PROG_FUNC6
J 0
(-6560 1310);
DISPLAY 0.553191 (-6560 1310);
FORCEPROP 2 LASTPROP $XRERR UNIQUE?
J 0
(-6800 1310);
DISPLAY 0.638298 (-6800 1310);
PAINT MONO (-6800 1310);
DISPLAY INVISIBLE (-6800 1310);
WIRE 16 -1 (-6575 1300)(-6775 1300);
WIRE 16 -1 (-6575 975)(-6575 1300);
WIRE 16 -1 (-6575 975)(-6725 975);
WIRE 16 -1 (-6925 975)(-7925 975);
FORCEPROP 2 LAST SIG_NAME USB_HUB2_TI_TEST
J 0
(-7760 1000);
DISPLAY 0.553191 (-7760 1000);
FORCEPROP 2 LASTPROP $XRERR UNIQUE?
J 0
(-8000 1000);
DISPLAY 0.638298 (-8000 1000);
PAINT MONO (-8000 1000);
DISPLAY INVISIBLE (-8000 1000);
WIRE 16 -1 (-7925 975)(-7925 875);
WIRE 16 -1 (-8500 1300)(-6975 1300);
FORCEPROP 2 LAST SIG_NAME USB_HUB2_MRP_PROG_FUNC6
J 0
(-8010 1325);
DISPLAY 0.702128 (-8010 1325);
FORCEPROP 2 LASTPROP $XRERR UNIQUE?
J 0
(-8250 1325);
DISPLAY 0.638298 (-8250 1325);
PAINT MONO (-8250 1325);
DISPLAY INVISIBLE (-8250 1325);
WIRE 16 -1 (-8500 1300)(-8500 1375);
WIRE 16 -1 (-8500 1200)(-8500 1300);
WIRE 16 -1 (-6575 1600)(-8025 1600);
FORCEPROP 2 LAST SIG_NAME USB_HUB2_MRP_I2C_SLV_CFG1
J 0
(-7810 1625);
DISPLAY 0.680851 (-7810 1625);
FORCEPROP 2 LASTPROP $XRERR UNIQUE?
J 0
(-8050 1625);
DISPLAY 0.638298 (-8050 1625);
PAINT MONO (-8050 1625);
DISPLAY INVISIBLE (-8050 1625);
WIRE 16 -1 (-8025 1600)(-8025 1825);
WIRE 16 -1 (-7025 2450)(-9200 2450);
FORCEPROP 2 LAST SIG_NAME USB_HUB2_TI_OVERCUR3
J 0
(-8610 2475);
DISPLAY 0.680851 (-8610 2475);
FORCEPROP 2 LASTPROP $XRERR UNIQUE?
J 0
(-8850 2475);
DISPLAY 0.638298 (-8850 2475);
PAINT MONO (-8850 2475);
DISPLAY INVISIBLE (-8850 2475);
WIRE 16 -1 (-9200 2975)(-9200 2450);
WIRE 16 -1 (-6975 2600)(-5625 2600);
FORCEPROP 2 LAST SIG_NAME USB_HUB2_TI_OVERCUR2_MRP_PROG_FUNC5
J 0
(-6910 2625);
DISPLAY 0.680851 (-6910 2625);
FORCEPROP 2 LASTPROP $XRERR UNIQUE?
J 0
(-7150 2625);
DISPLAY 0.638298 (-7150 2625);
PAINT MONO (-7150 2625);
DISPLAY INVISIBLE (-7150 2625);
WIRE 16 -1 (-6975 2600)(-6975 2525);
WIRE 16 -1 (-7475 2600)(-6975 2600);
FORCEPROP 0 LAST $PNN USB_HUB2_TI_OVERCUR2_MRP_PROG_F
J 0
(-7235 2642);
DISPLAY INVISIBLE (-7235 2642);
WIRE 16 -1 (-6975 2525)(-7450 2525);
WIRE 16 -1 (-7950 2750)(-7025 2750);
FORCEPROP 2 LAST SIG_NAME SMB_USB_CPU0_HUB1_SDA
J 0
(-7935 2760);
DISPLAY 0.680851 (-7935 2760);
WIRE 16 -1 (-5625 2300)(-5850 2300);
WIRE 16 -1 (-5850 2300)(-5850 1725);
FORCEPROP 2 LAST SIG_NAME USB_HUB2_TI_OVERCUR4_MRP_I2C_SLV_CFG1
J 0
(-7035 2035);
DISPLAY 0.680851 (-7035 2035);
FORCEPROP 2 LASTPROP $XRERR UNIQUE?
J 0
(-7275 2035);
DISPLAY 0.638298 (-7275 2035);
PAINT MONO (-7275 2035);
DISPLAY INVISIBLE (-7275 2035);
WIRE 16 -1 (-5850 1725)(-5850 1600);
WIRE 16 -1 (-6400 1725)(-5850 1725);
WIRE 16 -1 (-6375 1600)(-5850 1600);
WIRE 16 -1 (-6600 1725)(-7575 1725);
FORCEPROP 2 LAST SIG_NAME USB_HUB2_TI_OVERCCUR4
J 0
(-7510 1750);
DISPLAY 0.680851 (-7510 1750);
FORCEPROP 2 LASTPROP $XRERR UNIQUE?
J 0
(-7750 1750);
DISPLAY 0.638298 (-7750 1750);
PAINT MONO (-7750 1750);
DISPLAY INVISIBLE (-7750 1750);
WIRE 16 -1 (-7575 1825)(-7575 1725);
WIRE 16 -1 (-4925 800)(-6100 800);
FORCEPROP 2 LAST SIG_NAME USB_HUB2_TI_NC_MRP_ATEST
J 0
(-5785 825);
DISPLAY 0.702128 (-5785 825);
WIRE 16 -1 (-7100 2325)(-8800 2325);
FORCEPROP 2 LAST SIG_NAME USB_HUB2_MRP_CFG_BC_EN
J 0
(-8160 2350);
DISPLAY 0.702128 (-8160 2350);
FORCEPROP 2 LASTPROP $XRERR UNIQUE?
J 0
(-8400 2350);
DISPLAY 0.638298 (-8400 2350);
PAINT MONO (-8400 2350);
DISPLAY INVISIBLE (-8400 2350);
WIRE 16 -1 (-8800 1925)(-8800 2325);
WIRE 16 -1 (-9075 1925)(-8800 1925);
WIRE 16 -1 (-9075 1925)(-9075 2025);
WIRE 16 -1 (-9075 1750)(-9075 1925);
WIRE 16 -1 (-6300 2450)(-5625 2450);
WIRE 16 -1 (-6300 2450)(-6300 2325);
WIRE 16 -1 (-6825 2450)(-6300 2450);
FORCEPROP 2 LAST SIG_NAME USB_HUB2_TI_OVERCUR3_MRP_CFG_BC_EN
J 0
(-6610 2475);
DISPLAY 0.553191 (-6610 2475);
FORCEPROP 2 LASTPROP $XRERR UNIQUE?
J 0
(-6850 2475);
DISPLAY 0.638298 (-6850 2475);
PAINT MONO (-6850 2475);
DISPLAY INVISIBLE (-6850 2475);
FORCEPROP 0 LAST $PNN USB_HUB2_TI_OVERCUR3_MRP_CFG_BC
J 0
(-6310 2486);
DISPLAY INVISIBLE (-6310 2486);
WIRE 16 -1 (-6300 2325)(-6900 2325);
WIRE 16 -1 (-8700 2525)(-7650 2525);
FORCEPROP 2 LAST SIG_NAME SMB_USB_CPU0_HUB1_SCL
J 0
(-8610 2535);
DISPLAY 0.680851 (-8610 2535);
WIRE 16 -1 (-6825 2750)(-6650 2750);
FORCEPROP 0 LAST $PNN USB_HUB2_TI_OVERCUR1_MRP_PROG_F
J 0
(-6735 2786);
DISPLAY INVISIBLE (-6735 2786);
WIRE 16 -1 (-6650 2750)(-5625 2750);
FORCEPROP 2 LAST SIG_NAME USB_HUB2_TI_OVERCUR1_MRP_PROG_FUNC4
J 0
(-6635 2775);
DISPLAY 0.553191 (-6635 2775);
FORCEPROP 2 LASTPROP $XRERR UNIQUE?
J 0
(-6875 2775);
DISPLAY 0.638298 (-6875 2775);
PAINT MONO (-6875 2775);
DISPLAY INVISIBLE (-6875 2775);
WIRE 16 -1 (-6650 2950)(-6650 2750);
WIRE 16 -1 (-6800 2950)(-6650 2950);
WIRE 16 -1 (-8750 2600)(-7675 2600);
FORCEPROP 2 LAST SIG_NAME USB_HUB2_TI_OVERCUR2
J 0
(-8660 2625);
DISPLAY 0.680851 (-8660 2625);
FORCEPROP 2 LASTPROP $XRERR UNIQUE?
J 0
(-8900 2625);
DISPLAY 0.638298 (-8900 2625);
PAINT MONO (-8900 2625);
DISPLAY INVISIBLE (-8900 2625);
WIRE 16 -1 (-8750 2850)(-8750 2600);
WIRE 16 -1 (-8025 2950)(-7000 2950);
FORCEPROP 2 LAST SIG_NAME USB_HUB2_TI_OVERCUR1
J 0
(-7760 2975);
DISPLAY 0.553191 (-7760 2975);
FORCEPROP 2 LASTPROP $XRERR UNIQUE?
J 0
(-8000 2975);
DISPLAY 0.638298 (-8000 2975);
PAINT MONO (-8000 2975);
DISPLAY INVISIBLE (-8000 2975);
WIRE 16 -1 (-5625 3600)(-7575 3600);
FORCEPROP 2 LAST SIG_NAME USB_HUB2_TI_GRSTZ_MRP_PROG_FUNC1
J 0
(-6660 3625);
DISPLAY 0.553191 (-6660 3625);
FORCEPROP 2 LASTPROP $XRERR UNIQUE?
J 0
(-6900 3625);
DISPLAY 0.638298 (-6900 3625);
PAINT MONO (-6900 3625);
DISPLAY INVISIBLE (-6900 3625);
FORCEPROP 0 LAST $PNN USB_HUB2_TI_GRSTZ_MRP_PROG_FUNC
J 0
(-6535 3636);
DISPLAY INVISIBLE (-6535 3636);
WIRE 16 -1 (-7575 3550)(-7575 3600);
WIRE 16 -1 (-7575 3600)(-8175 3600);
WIRE 16 -1 (-8175 3600)(-8175 3725);
WIRE 16 -1 (-8175 3600)(-8175 3525);
WIRE 16 -1 (-8175 3600)(-8250 3600);
WIRE 16 -1 (-8975 3600)(-8450 3600);
FORCEPROP 2 LAST SIG_NAME RST_USB_HUB_N
J 0
(-8960 3635);
DISPLAY 0.680851 (-8960 3635);
WIRE 16 -1 (-7100 3900)(-5625 3900);
FORCEPROP 2 LAST SIG_NAME USB_HUB2_TI_PWRCTL3_MRP_VDD33
J 0
(-6710 3925);
DISPLAY 0.680851 (-6710 3925);
FORCEPROP 2 LASTPROP $XRERR UNIQUE?
J 0
(-6950 3925);
DISPLAY 0.638298 (-6950 3925);
PAINT MONO (-6950 3925);
DISPLAY INVISIBLE (-6950 3925);
WIRE 16 -1 (-6975 4275)(-6825 4275);
WIRE 16 -1 (-6825 4275)(-6825 4050);
WIRE 16 -1 (-5625 4050)(-6825 4050);
FORCEPROP 2 LAST SIG_NAME USB_HUB2_TI_PWRCTL2_MRP_VDD12
J 0
(-6660 4075);
DISPLAY 0.680851 (-6660 4075);
FORCEPROP 2 LASTPROP $XRERR UNIQUE?
J 0
(-6900 4075);
DISPLAY 0.638298 (-6900 4075);
PAINT MONO (-6900 4075);
DISPLAY INVISIBLE (-6900 4075);
WIRE 16 -1 (-6825 4050)(-6950 4050);
WIRE 16 -1 (-7250 5100)(-7250 4625);
WIRE 16 -1 (-7250 5100)(-7750 5100);
WIRE 16 -1 (-7250 4625)(-5700 4625);
FORCEPROP 2 LAST SIG_NAME USB_HUB2_TI_PWRCTL_POL_MRP_VBUS_DET
J 0
(-7060 4650);
DISPLAY 0.680851 (-7060 4650);
FORCEPROP 2 LASTPROP $XRERR UNIQUE?
J 0
(-7300 4650);
DISPLAY 0.638298 (-7300 4650);
PAINT MONO (-7300 4650);
DISPLAY INVISIBLE (-7300 4650);
FORCEPROP 0 LAST $PNN USB_HUB2_TI_PWRCTL_POL_MRP_VBUS
J 0
(-7110 4667);
DISPLAY INVISIBLE (-7110 4667);
WIRE 16 -1 (-7725 4625)(-7250 4625);
WIRE 16 -1 (-5700 4625)(-5700 4350);
WIRE 16 -1 (-5700 4350)(-5625 4350);
WIRE 16 -1 (-5625 4900)(-6525 4900);
FORCEPROP 2 LAST SIG_NAME USB3_CPU0_BMC_TX_C2_DN
J 0
(-6460 4910);
DISPLAY 0.680851 (-6460 4910);
WIRE 16 -1 (-9175 4625)(-7925 4625);
FORCEPROP 2 LAST SIG_NAME USB_HUB2_MRP_VBUS_DET
J 0
(-8935 4650);
DISPLAY 0.680851 (-8935 4650);
FORCEPROP 2 LASTPROP $XRERR UNIQUE?
J 0
(-9175 4650);
DISPLAY 0.638298 (-9175 4650);
PAINT MONO (-9175 4650);
DISPLAY INVISIBLE (-9175 4650);
WIRE 16 -1 (-9175 4625)(-9175 4750);
WIRE 16 -1 (-7950 5100)(-8675 5100);
FORCEPROP 2 LAST SIG_NAME USB_HUB2_TI_PWRCTL_POL
J 0
(-8535 5110);
DISPLAY 0.553191 (-8535 5110);
FORCEPROP 2 LASTPROP $XRERR UNIQUE?
J 0
(-8775 5110);
DISPLAY 0.638298 (-8775 5110);
PAINT MONO (-8775 5110);
DISPLAY INVISIBLE (-8775 5110);
WIRE 16 -1 (-8675 5100)(-8675 5150);
WIRE 16 -1 (-8675 5075)(-8675 5100);
WIRE 16 -1 (-9100 5500)(-9100 5550);
WIRE 16 -1 (-9100 5550)(-7075 5550);
FORCEPROP 2 LAST SIG_NAME USB_HUB2_TI_USB_VBUS
J 0
(-8510 5560);
DISPLAY 0.680851 (-8510 5560);
FORCEPROP 2 LASTPROP $XRERR UNIQUE?
J 0
(-8750 5560);
DISPLAY 0.638298 (-8750 5560);
PAINT MONO (-8750 5560);
DISPLAY INVISIBLE (-8750 5560);
WIRE 16 -1 (-9100 5550)(-9100 5650);
WIRE 16 -1 (-6525 5100)(-5625 5100);
FORCEPROP 2 LAST SIG_NAME USB3_CPU0_BMC_RX_HUB2_DN
J 0
(-6535 5110);
DISPLAY 0.680851 (-6535 5110);
WIRE 16 -1 (-6525 5150)(-5625 5150);
FORCEPROP 2 LAST SIG_NAME USB3_CPU0_BMC_RX_HUB2_DP
J 0
(-6535 5160);
DISPLAY 0.680851 (-6535 5160);
WIRE 16 -1 (-6500 5300)(-5625 5300);
FORCEPROP 2 LAST SIG_NAME USB2_CPU0_P0_R2_DN
J 0
(-6385 5310);
DISPLAY 0.680851 (-6385 5310);
WIRE 16 -1 (-6500 5350)(-5625 5350);
FORCEPROP 2 LAST SIG_NAME USB2_CPU0_P0_R2_DP
J 0
(-6385 5360);
DISPLAY 0.680851 (-6385 5360);
WIRE 16 -1 (-8025 5975)(-8025 6025);
WIRE 16 -1 (-8025 6200)(-8025 6025);
WIRE 16 -1 (-7075 6025)(-8025 6025);
FORCEPROP 2 LAST SIG_NAME USB_HUB2_MRP_RESET_N
J 0
(-7960 6035);
DISPLAY 0.680851 (-7960 6035);
FORCEPROP 2 LASTPROP $XRERR UNIQUE?
J 0
(-8200 6035);
DISPLAY 0.638298 (-8200 6035);
PAINT MONO (-8200 6035);
DISPLAY INVISIBLE (-8200 6035);
WIRE 16 -1 (-8025 6025)(-8350 6025);
WIRE 16 -1 (-8350 6275)(-8350 6025);
WIRE 16 -1 (-8350 6025)(-8350 6000);
WIRE 16 -1 (-8500 6275)(-8350 6275);
WIRE 16 -1 (-9100 6275)(-8700 6275);
FORCEPROP 2 LAST SIG_NAME RST_USB_HUB_N
J 0
(-9135 6285);
DISPLAY 0.680851 (-9135 6285);
WIRE 16 -1 (-4075 3850)(-3100 3850);
FORCEPROP 2 LAST SIG_NAME USB3_CPU0_BMC_HUB2_TX_DN
J 0
(-3910 3860);
DISPLAY 0.680851 (-3910 3860);
WIRE 16 -1 (-4075 3900)(-3100 3900);
FORCEPROP 2 LAST SIG_NAME USB3_CPU0_BMC_HUB2_TX_DP
J 0
(-3910 3910);
DISPLAY 0.680851 (-3910 3910);
WIRE 16 -1 (-5625 4950)(-6525 4950);
FORCEPROP 2 LAST SIG_NAME USB3_CPU0_BMC_TX_C2_DP
J 0
(-6485 4960);
DISPLAY 0.680851 (-6485 4960);
DOT 1 (-8350 6025);
DOT 1 (-7575 3600);
DOT 1 (-1000 5350);
DOT 1 (-8500 1300);
DOT 1 (-9100 5550);
DOT 1 (-6675 5550);
DOT 1 (-8175 3600);
DOT 1 (-8025 6025);
DOT 1 (-7250 4625);
DOT 1 (-8675 5100);
DOT 1 (-6825 4050);
DOT 1 (-6650 2750);
DOT 1 (-6975 2600);
DOT 1 (-6300 2450);
DOT 1 (-9075 1925);
DOT 1 (-6575 1300);
DOT 1 (-5850 1725);
DOT 1 (-3000 1500);
FORCENOTE
MFR:MRP
(-4475 6300) 0;
DISPLAY LEFT (-4475 6300);
DISPLAY 1.276596 (-4475 6300);
FORCENOTE
MFR PN:USB5734T/M
(-4475 6375) 0;
DISPLAY LEFT (-4475 6375);
DISPLAY 1.276596 (-4475 6375);
FORCENOTE
QPN:AL005734000
(-4475 6450) 0;
DISPLAY LEFT (-4475 6450);
DISPLAY 1.276596 (-4475 6450);
FORCENOTE
2ND
(-5925 6550) 0;
DISPLAY LEFT (-5925 6550);
DISPLAY 1.276596 (-5925 6550);
FORCENOTE
3RD
(-4500 6525) 0;
DISPLAY LEFT (-4500 6525);
DISPLAY 1.276596 (-4500 6525);
FORCENOTE
QPN:AL008042000
(-5925 6475) 0;
DISPLAY LEFT (-5925 6475);
DISPLAY 1.276596 (-5925 6475);
FORCENOTE
MFR PN:TUSB8042AIRGCR
(-5925 6400) 0;
DISPLAY LEFT (-5925 6400);
DISPLAY 1.276596 (-5925 6400);
FORCENOTE
MFR:TI
(-5925 6325) 0;
DISPLAY LEFT (-5925 6325);
DISPLAY 1.276596 (-5925 6325);
QUIT
